FILE_TYPE = MACRO_DRAWING;
SET COLOR_WIRE YELLOW;
SET COLOR_PROP ORANGE;
SET COLOR_DOT WHITE;
SET COLOR_ARC YELLOW;
SET COLOR_BODY GREEN;
SET COLOR_NOTE PURPLE;
SET PROP_DISPLAY VALUE;
SET PAGE_NUMBER P14;
FORCEADD GENOA_SP5..5
(-4675 3675);
FORCEPROP 1 LAST LOCATION U25
J 0
(-5320 6506);
DISPLAY 0.489362 (-5320 6506);
PAINT SKYBLUE (-5320 6506);
FORCEPROP 0 LAST $SEC 5
J 0
(-5300 6550);
DISPLAY 0.680851 (-5300 6550);
PAINT MONO (-5300 6550);
DISPLAY INVISIBLE (-5300 6550);
FORCEPROP 0 LAST CDS_SEC 5
J 0
(-5325 6500);
DISPLAY 1.021277 (-5325 6500);
DISPLAY INVISIBLE (-5325 6500);
FORCEPROP 0 LASTPIN (-5475 3050) $PN BC71
J 2
(-5485 3060);
DISPLAY 0.489362 (-5485 3060);
PAINT MONO (-5485 3060);
FORCEPROP 0 LASTPIN (-5475 3000) $PN BD70
J 2
(-5485 3010);
DISPLAY 0.489362 (-5485 3010);
PAINT MONO (-5485 3010);
FORCEPROP 0 LASTPIN (-5475 1900) $PN BF70
J 2
(-5485 1910);
DISPLAY 0.489362 (-5485 1910);
PAINT MONO (-5485 1910);
FORCEPROP 0 LASTPIN (-5475 1850) $PN BG71
J 2
(-5485 1860);
DISPLAY 0.489362 (-5485 1860);
PAINT MONO (-5485 1860);
FORCEPROP 0 LASTPIN (-5475 2200) $PN AT69
J 2
(-5485 2210);
DISPLAY 0.489362 (-5485 2210);
PAINT MONO (-5485 2210);
FORCEPROP 0 LASTPIN (-5475 2100) $PN AU69
J 2
(-5485 2110);
DISPLAY 0.489362 (-5485 2110);
PAINT MONO (-5485 2110);
FORCEPROP 0 LASTPIN (-5475 2900) $PN AV70
J 2
(-5485 2910);
DISPLAY 0.489362 (-5485 2910);
PAINT MONO (-5485 2910);
FORCEPROP 0 LASTPIN (-5475 2850) $PN AW69
J 2
(-5485 2860);
DISPLAY 0.489362 (-5485 2860);
PAINT MONO (-5485 2860);
FORCEPROP 0 LASTPIN (-5475 2750) $PN BN69
J 2
(-5485 2760);
DISPLAY 0.489362 (-5485 2760);
PAINT MONO (-5485 2760);
FORCEPROP 0 LASTPIN (-5475 1750) $PN AU71
J 2
(-5485 1760);
DISPLAY 0.489362 (-5485 1760);
PAINT MONO (-5485 1760);
FORCEPROP 0 LASTPIN (-5475 1700) $PN AV69
J 2
(-5485 1710);
DISPLAY 0.489362 (-5485 1710);
PAINT MONO (-5485 1710);
FORCEPROP 0 LASTPIN (-5475 1600) $PN BP69
J 2
(-5485 1610);
DISPLAY 0.489362 (-5485 1610);
PAINT MONO (-5485 1610);
FORCEPROP 0 LASTPIN (-5475 3900) $PN AW71
J 2
(-5485 3910);
DISPLAY 0.489362 (-5485 3910);
PAINT MONO (-5485 3910);
FORCEPROP 0 LASTPIN (-5475 3850) $PN AY70
J 2
(-5485 3860);
DISPLAY 0.489362 (-5485 3860);
PAINT MONO (-5485 3860);
FORCEPROP 0 LASTPIN (-5475 3800) $PN AY69
J 2
(-5485 3810);
DISPLAY 0.489362 (-5485 3810);
PAINT MONO (-5485 3810);
FORCEPROP 0 LASTPIN (-5475 3750) $PN BA69
J 2
(-5485 3760);
DISPLAY 0.489362 (-5485 3760);
PAINT MONO (-5485 3760);
FORCEPROP 0 LASTPIN (-5475 3700) $PN BA71
J 2
(-5485 3710);
DISPLAY 0.489362 (-5485 3710);
PAINT MONO (-5485 3710);
FORCEPROP 0 LASTPIN (-5475 3650) $PN BB70
J 2
(-5485 3660);
DISPLAY 0.489362 (-5485 3660);
PAINT MONO (-5485 3660);
FORCEPROP 0 LASTPIN (-5475 3600) $PN BB69
J 2
(-5485 3610);
DISPLAY 0.489362 (-5485 3610);
PAINT MONO (-5485 3610);
FORCEPROP 0 LASTPIN (-3875 2450) $PN AJ71
J 0
(-3865 2460);
DISPLAY 0.489362 (-3865 2460);
PAINT MONO (-3865 2460);
FORCEPROP 0 LASTPIN (-3875 2400) $PN AK69
J 0
(-3865 2410);
DISPLAY 0.489362 (-3865 2410);
PAINT MONO (-3865 2410);
FORCEPROP 0 LASTPIN (-3875 2350) $PN AK70
J 0
(-3865 2360);
DISPLAY 0.489362 (-3865 2360);
PAINT MONO (-3865 2360);
FORCEPROP 0 LASTPIN (-3875 2300) $PN AL69
J 0
(-3865 2310);
DISPLAY 0.489362 (-3865 2310);
PAINT MONO (-3865 2310);
FORCEPROP 0 LASTPIN (-3875 2250) $PN AN71
J 0
(-3865 2260);
DISPLAY 0.489362 (-3865 2260);
PAINT MONO (-3865 2260);
FORCEPROP 0 LASTPIN (-3875 2200) $PN AP69
J 0
(-3865 2210);
DISPLAY 0.489362 (-3865 2210);
PAINT MONO (-3865 2210);
FORCEPROP 0 LASTPIN (-3875 2150) $PN AP70
J 0
(-3865 2160);
DISPLAY 0.489362 (-3865 2160);
PAINT MONO (-3865 2160);
FORCEPROP 0 LASTPIN (-3875 2100) $PN AR69
J 0
(-3865 2110);
DISPLAY 0.489362 (-3865 2110);
PAINT MONO (-3865 2110);
FORCEPROP 0 LASTPIN (-3875 6050) $PN E71
J 0
(-3865 6060);
DISPLAY 0.489362 (-3865 6060);
PAINT MONO (-3865 6060);
FORCEPROP 0 LASTPIN (-3875 6000) $PN F69
J 0
(-3865 6010);
DISPLAY 0.489362 (-3865 6010);
PAINT MONO (-3865 6010);
FORCEPROP 0 LASTPIN (-3875 5950) $PN F70
J 0
(-3865 5960);
DISPLAY 0.489362 (-3865 5960);
PAINT MONO (-3865 5960);
FORCEPROP 0 LASTPIN (-3875 5900) $PN G69
J 0
(-3865 5910);
DISPLAY 0.489362 (-3865 5910);
PAINT MONO (-3865 5910);
FORCEPROP 0 LASTPIN (-3875 5850) $PN J71
J 0
(-3865 5860);
DISPLAY 0.489362 (-3865 5860);
PAINT MONO (-3865 5860);
FORCEPROP 0 LASTPIN (-3875 5800) $PN K69
J 0
(-3865 5810);
DISPLAY 0.489362 (-3865 5810);
PAINT MONO (-3865 5810);
FORCEPROP 0 LASTPIN (-3875 5750) $PN K70
J 0
(-3865 5760);
DISPLAY 0.489362 (-3865 5760);
PAINT MONO (-3865 5760);
FORCEPROP 0 LASTPIN (-3875 5700) $PN L69
J 0
(-3865 5710);
DISPLAY 0.489362 (-3865 5710);
PAINT MONO (-3865 5710);
FORCEPROP 0 LASTPIN (-3875 5600) $PN L71
J 0
(-3865 5610);
DISPLAY 0.489362 (-3865 5610);
PAINT MONO (-3865 5610);
FORCEPROP 0 LASTPIN (-3875 5550) $PN M69
J 0
(-3865 5560);
DISPLAY 0.489362 (-3865 5560);
PAINT MONO (-3865 5560);
FORCEPROP 0 LASTPIN (-3875 5500) $PN M70
J 0
(-3865 5510);
DISPLAY 0.489362 (-3865 5510);
PAINT MONO (-3865 5510);
FORCEPROP 0 LASTPIN (-3875 5450) $PN N69
J 0
(-3865 5460);
DISPLAY 0.489362 (-3865 5460);
PAINT MONO (-3865 5460);
FORCEPROP 0 LASTPIN (-3875 5400) $PN R71
J 0
(-3865 5410);
DISPLAY 0.489362 (-3865 5410);
PAINT MONO (-3865 5410);
FORCEPROP 0 LASTPIN (-3875 5350) $PN T69
J 0
(-3865 5360);
DISPLAY 0.489362 (-3865 5360);
PAINT MONO (-3865 5360);
FORCEPROP 0 LASTPIN (-3875 5300) $PN T70
J 0
(-3865 5310);
DISPLAY 0.489362 (-3865 5310);
PAINT MONO (-3865 5310);
FORCEPROP 0 LASTPIN (-3875 5250) $PN U69
J 0
(-3865 5260);
DISPLAY 0.489362 (-3865 5260);
PAINT MONO (-3865 5260);
FORCEPROP 0 LASTPIN (-3875 5150) $PN U71
J 0
(-3865 5160);
DISPLAY 0.489362 (-3865 5160);
PAINT MONO (-3865 5160);
FORCEPROP 0 LASTPIN (-3875 5100) $PN V69
J 0
(-3865 5110);
DISPLAY 0.489362 (-3865 5110);
PAINT MONO (-3865 5110);
FORCEPROP 0 LASTPIN (-3875 5050) $PN V70
J 0
(-3865 5060);
DISPLAY 0.489362 (-3865 5060);
PAINT MONO (-3865 5060);
FORCEPROP 0 LASTPIN (-3875 5000) $PN W69
J 0
(-3865 5010);
DISPLAY 0.489362 (-3865 5010);
PAINT MONO (-3865 5010);
FORCEPROP 0 LASTPIN (-3875 4950) $PN AA71
J 0
(-3865 4960);
DISPLAY 0.489362 (-3865 4960);
PAINT MONO (-3865 4960);
FORCEPROP 0 LASTPIN (-3875 4900) $PN AB69
J 0
(-3865 4910);
DISPLAY 0.489362 (-3865 4910);
PAINT MONO (-3865 4910);
FORCEPROP 0 LASTPIN (-3875 4850) $PN AB70
J 0
(-3865 4860);
DISPLAY 0.489362 (-3865 4860);
PAINT MONO (-3865 4860);
FORCEPROP 0 LASTPIN (-3875 4800) $PN AC69
J 0
(-3865 4810);
DISPLAY 0.489362 (-3865 4810);
PAINT MONO (-3865 4810);
FORCEPROP 0 LASTPIN (-3875 4700) $PN AC71
J 0
(-3865 4710);
DISPLAY 0.489362 (-3865 4710);
PAINT MONO (-3865 4710);
FORCEPROP 0 LASTPIN (-3875 4650) $PN AD69
J 0
(-3865 4660);
DISPLAY 0.489362 (-3865 4660);
PAINT MONO (-3865 4660);
FORCEPROP 0 LASTPIN (-3875 4600) $PN AD70
J 0
(-3865 4610);
DISPLAY 0.489362 (-3865 4610);
PAINT MONO (-3865 4610);
FORCEPROP 0 LASTPIN (-3875 4550) $PN AE69
J 0
(-3865 4560);
DISPLAY 0.489362 (-3865 4560);
PAINT MONO (-3865 4560);
FORCEPROP 0 LASTPIN (-3875 4500) $PN AG71
J 0
(-3865 4510);
DISPLAY 0.489362 (-3865 4510);
PAINT MONO (-3865 4510);
FORCEPROP 0 LASTPIN (-3875 4450) $PN AH69
J 0
(-3865 4460);
DISPLAY 0.489362 (-3865 4460);
PAINT MONO (-3865 4460);
FORCEPROP 0 LASTPIN (-3875 4400) $PN AH70
J 0
(-3865 4410);
DISPLAY 0.489362 (-3865 4410);
PAINT MONO (-3865 4410);
FORCEPROP 0 LASTPIN (-3875 4350) $PN AJ69
J 0
(-3865 4360);
DISPLAY 0.489362 (-3865 4360);
PAINT MONO (-3865 4360);
FORCEPROP 0 LASTPIN (-5475 6050) $PN G71
J 2
(-5485 6060);
DISPLAY 0.489362 (-5485 6060);
PAINT MONO (-5485 6060);
FORCEPROP 0 LASTPIN (-5475 5950) $PN N71
J 2
(-5485 5960);
DISPLAY 0.489362 (-5485 5960);
PAINT MONO (-5485 5960);
FORCEPROP 0 LASTPIN (-5475 5850) $PN W71
J 2
(-5485 5860);
DISPLAY 0.489362 (-5485 5860);
PAINT MONO (-5485 5860);
FORCEPROP 0 LASTPIN (-5475 5750) $PN AE71
J 2
(-5485 5760);
DISPLAY 0.489362 (-5485 5760);
PAINT MONO (-5485 5760);
FORCEPROP 0 LASTPIN (-5475 5650) $PN AL71
J 2
(-5485 5660);
DISPLAY 0.489362 (-5485 5660);
PAINT MONO (-5485 5660);
FORCEPROP 0 LASTPIN (-5475 5550) $PN J69
J 2
(-5485 5560);
DISPLAY 0.489362 (-5485 5560);
PAINT MONO (-5485 5560);
FORCEPROP 0 LASTPIN (-5475 5450) $PN R69
J 2
(-5485 5460);
DISPLAY 0.489362 (-5485 5460);
PAINT MONO (-5485 5460);
FORCEPROP 0 LASTPIN (-5475 5350) $PN AA69
J 2
(-5485 5360);
DISPLAY 0.489362 (-5485 5360);
PAINT MONO (-5485 5360);
FORCEPROP 0 LASTPIN (-5475 5250) $PN AG69
J 2
(-5485 5260);
DISPLAY 0.489362 (-5485 5260);
PAINT MONO (-5485 5260);
FORCEPROP 0 LASTPIN (-5475 5150) $PN AN69
J 2
(-5485 5160);
DISPLAY 0.489362 (-5485 5160);
PAINT MONO (-5485 5160);
FORCEPROP 0 LASTPIN (-5475 6000) $PN H70
J 2
(-5485 6010);
DISPLAY 0.489362 (-5485 6010);
PAINT MONO (-5485 6010);
FORCEPROP 0 LASTPIN (-5475 5900) $PN P70
J 2
(-5485 5910);
DISPLAY 0.489362 (-5485 5910);
PAINT MONO (-5485 5910);
FORCEPROP 0 LASTPIN (-5475 5800) $PN Y70
J 2
(-5485 5810);
DISPLAY 0.489362 (-5485 5810);
PAINT MONO (-5485 5810);
FORCEPROP 0 LASTPIN (-5475 5700) $PN AF70
J 2
(-5485 5710);
DISPLAY 0.489362 (-5485 5710);
PAINT MONO (-5485 5710);
FORCEPROP 0 LASTPIN (-5475 5600) $PN AM70
J 2
(-5485 5610);
DISPLAY 0.489362 (-5485 5610);
PAINT MONO (-5485 5610);
FORCEPROP 0 LASTPIN (-5475 5500) $PN H69
J 2
(-5485 5510);
DISPLAY 0.489362 (-5485 5510);
PAINT MONO (-5485 5510);
FORCEPROP 0 LASTPIN (-5475 5400) $PN P69
J 2
(-5485 5410);
DISPLAY 0.489362 (-5485 5410);
PAINT MONO (-5485 5410);
FORCEPROP 0 LASTPIN (-5475 5300) $PN Y69
J 2
(-5485 5310);
DISPLAY 0.489362 (-5485 5310);
PAINT MONO (-5485 5310);
FORCEPROP 0 LASTPIN (-5475 5200) $PN AF69
J 2
(-5485 5210);
DISPLAY 0.489362 (-5485 5210);
PAINT MONO (-5485 5210);
FORCEPROP 0 LASTPIN (-5475 5100) $PN AM69
J 2
(-5485 5110);
DISPLAY 0.489362 (-5485 5110);
PAINT MONO (-5485 5110);
FORCEPROP 0 LASTPIN (-5475 2650) $PN BC69
J 2
(-5485 2660);
DISPLAY 0.489362 (-5485 2660);
PAINT MONO (-5485 2660);
FORCEPROP 0 LASTPIN (-5475 2550) $PN BM69
J 2
(-5485 2560);
DISPLAY 0.489362 (-5485 2560);
PAINT MONO (-5485 2560);
FORCEPROP 0 LASTPIN (-5475 2500) $PN BN71
J 2
(-5485 2510);
DISPLAY 0.489362 (-5485 2510);
PAINT MONO (-5485 2510);
FORCEPROP 0 LASTPIN (-5475 2400) $PN BP70
J 2
(-5485 2410);
DISPLAY 0.489362 (-5485 2410);
PAINT MONO (-5485 2410);
FORCEPROP 0 LASTPIN (-5475 1500) $PN BL69
J 2
(-5485 1510);
DISPLAY 0.489362 (-5485 1510);
PAINT MONO (-5485 1510);
FORCEPROP 0 LASTPIN (-5475 1450) $PN BM70
J 2
(-5485 1460);
DISPLAY 0.489362 (-5485 1460);
PAINT MONO (-5485 1460);
FORCEPROP 0 LASTPIN (-5475 1350) $PN BR71
J 2
(-5485 1360);
DISPLAY 0.489362 (-5485 1360);
PAINT MONO (-5485 1360);
FORCEPROP 0 LASTPIN (-5475 3500) $PN BG69
J 2
(-5485 3510);
DISPLAY 0.489362 (-5485 3510);
PAINT MONO (-5485 3510);
FORCEPROP 0 LASTPIN (-5475 3450) $PN BH69
J 2
(-5485 3460);
DISPLAY 0.489362 (-5485 3460);
PAINT MONO (-5485 3460);
FORCEPROP 0 LASTPIN (-5475 3400) $PN BH70
J 2
(-5485 3410);
DISPLAY 0.489362 (-5485 3410);
PAINT MONO (-5485 3410);
FORCEPROP 0 LASTPIN (-5475 3350) $PN BJ71
J 2
(-5485 3360);
DISPLAY 0.489362 (-5485 3360);
PAINT MONO (-5485 3360);
FORCEPROP 0 LASTPIN (-5475 3300) $PN BJ69
J 2
(-5485 3310);
DISPLAY 0.489362 (-5485 3310);
PAINT MONO (-5485 3310);
FORCEPROP 0 LASTPIN (-5475 3250) $PN BK69
J 2
(-5485 3260);
DISPLAY 0.489362 (-5485 3260);
PAINT MONO (-5485 3260);
FORCEPROP 0 LASTPIN (-5475 3200) $PN BK70
J 2
(-5485 3210);
DISPLAY 0.489362 (-5485 3210);
PAINT MONO (-5485 3210);
FORCEPROP 0 LASTPIN (-3875 2000) $PN BY70
J 0
(-3865 2010);
DISPLAY 0.489362 (-3865 2010);
PAINT MONO (-3865 2010);
FORCEPROP 0 LASTPIN (-3875 1950) $PN CA69
J 0
(-3865 1960);
DISPLAY 0.489362 (-3865 1960);
PAINT MONO (-3865 1960);
FORCEPROP 0 LASTPIN (-3875 1900) $PN CA71
J 0
(-3865 1910);
DISPLAY 0.489362 (-3865 1910);
PAINT MONO (-3865 1910);
FORCEPROP 0 LASTPIN (-3875 1850) $PN CB69
J 0
(-3865 1860);
DISPLAY 0.489362 (-3865 1860);
PAINT MONO (-3865 1860);
FORCEPROP 0 LASTPIN (-3875 1800) $PN BT70
J 0
(-3865 1810);
DISPLAY 0.489362 (-3865 1810);
PAINT MONO (-3865 1810);
FORCEPROP 0 LASTPIN (-3875 1750) $PN BU69
J 0
(-3865 1760);
DISPLAY 0.489362 (-3865 1760);
PAINT MONO (-3865 1760);
FORCEPROP 0 LASTPIN (-3875 1700) $PN BU71
J 0
(-3865 1710);
DISPLAY 0.489362 (-3865 1710);
PAINT MONO (-3865 1710);
FORCEPROP 0 LASTPIN (-3875 1650) $PN BV69
J 0
(-3865 1660);
DISPLAY 0.489362 (-3865 1660);
PAINT MONO (-3865 1660);
FORCEPROP 0 LASTPIN (-3875 4250) $PN CB70
J 0
(-3865 4260);
DISPLAY 0.489362 (-3865 4260);
PAINT MONO (-3865 4260);
FORCEPROP 0 LASTPIN (-3875 4200) $PN CC69
J 0
(-3865 4210);
DISPLAY 0.489362 (-3865 4210);
PAINT MONO (-3865 4210);
FORCEPROP 0 LASTPIN (-3875 4150) $PN CC71
J 0
(-3865 4160);
DISPLAY 0.489362 (-3865 4160);
PAINT MONO (-3865 4160);
FORCEPROP 0 LASTPIN (-3875 4100) $PN CD69
J 0
(-3865 4110);
DISPLAY 0.489362 (-3865 4110);
PAINT MONO (-3865 4110);
FORCEPROP 0 LASTPIN (-3875 4050) $PN CF70
J 0
(-3865 4060);
DISPLAY 0.489362 (-3865 4060);
PAINT MONO (-3865 4060);
FORCEPROP 0 LASTPIN (-3875 4000) $PN CG69
J 0
(-3865 4010);
DISPLAY 0.489362 (-3865 4010);
PAINT MONO (-3865 4010);
FORCEPROP 0 LASTPIN (-3875 3950) $PN CG71
J 0
(-3865 3960);
DISPLAY 0.489362 (-3865 3960);
PAINT MONO (-3865 3960);
FORCEPROP 0 LASTPIN (-3875 3900) $PN CH69
J 0
(-3865 3910);
DISPLAY 0.489362 (-3865 3910);
PAINT MONO (-3865 3910);
FORCEPROP 0 LASTPIN (-3875 3800) $PN CH70
J 0
(-3865 3810);
DISPLAY 0.489362 (-3865 3810);
PAINT MONO (-3865 3810);
FORCEPROP 0 LASTPIN (-3875 3750) $PN CJ69
J 0
(-3865 3760);
DISPLAY 0.489362 (-3865 3760);
PAINT MONO (-3865 3760);
FORCEPROP 0 LASTPIN (-3875 3700) $PN CJ71
J 0
(-3865 3710);
DISPLAY 0.489362 (-3865 3710);
PAINT MONO (-3865 3710);
FORCEPROP 0 LASTPIN (-3875 3650) $PN CK69
J 0
(-3865 3660);
DISPLAY 0.489362 (-3865 3660);
PAINT MONO (-3865 3660);
FORCEPROP 0 LASTPIN (-3875 3600) $PN CM70
J 0
(-3865 3610);
DISPLAY 0.489362 (-3865 3610);
PAINT MONO (-3865 3610);
FORCEPROP 0 LASTPIN (-3875 3550) $PN CN69
J 0
(-3865 3560);
DISPLAY 0.489362 (-3865 3560);
PAINT MONO (-3865 3560);
FORCEPROP 0 LASTPIN (-3875 3500) $PN CN71
J 0
(-3865 3510);
DISPLAY 0.489362 (-3865 3510);
PAINT MONO (-3865 3510);
FORCEPROP 0 LASTPIN (-3875 3450) $PN CP69
J 0
(-3865 3460);
DISPLAY 0.489362 (-3865 3460);
PAINT MONO (-3865 3460);
FORCEPROP 0 LASTPIN (-3875 3350) $PN CP70
J 0
(-3865 3360);
DISPLAY 0.489362 (-3865 3360);
PAINT MONO (-3865 3360);
FORCEPROP 0 LASTPIN (-3875 3300) $PN CR69
J 0
(-3865 3310);
DISPLAY 0.489362 (-3865 3310);
PAINT MONO (-3865 3310);
FORCEPROP 0 LASTPIN (-3875 3250) $PN CR71
J 0
(-3865 3260);
DISPLAY 0.489362 (-3865 3260);
PAINT MONO (-3865 3260);
FORCEPROP 0 LASTPIN (-3875 3200) $PN CT69
J 0
(-3865 3210);
DISPLAY 0.489362 (-3865 3210);
PAINT MONO (-3865 3210);
FORCEPROP 0 LASTPIN (-3875 3150) $PN CV70
J 0
(-3865 3160);
DISPLAY 0.489362 (-3865 3160);
PAINT MONO (-3865 3160);
FORCEPROP 0 LASTPIN (-3875 3100) $PN CW69
J 0
(-3865 3110);
DISPLAY 0.489362 (-3865 3110);
PAINT MONO (-3865 3110);
FORCEPROP 0 LASTPIN (-3875 3050) $PN CW71
J 0
(-3865 3060);
DISPLAY 0.489362 (-3865 3060);
PAINT MONO (-3865 3060);
FORCEPROP 0 LASTPIN (-3875 3000) $PN CY69
J 0
(-3865 3010);
DISPLAY 0.489362 (-3865 3010);
PAINT MONO (-3865 3010);
FORCEPROP 0 LASTPIN (-3875 2900) $PN CY70
J 0
(-3865 2910);
DISPLAY 0.489362 (-3865 2910);
PAINT MONO (-3865 2910);
FORCEPROP 0 LASTPIN (-3875 2850) $PN DA69
J 0
(-3865 2860);
DISPLAY 0.489362 (-3865 2860);
PAINT MONO (-3865 2860);
FORCEPROP 0 LASTPIN (-3875 2800) $PN DA71
J 0
(-3865 2810);
DISPLAY 0.489362 (-3865 2810);
PAINT MONO (-3865 2810);
FORCEPROP 0 LASTPIN (-3875 2750) $PN DB69
J 0
(-3865 2760);
DISPLAY 0.489362 (-3865 2760);
PAINT MONO (-3865 2760);
FORCEPROP 0 LASTPIN (-3875 2700) $PN DD70
J 0
(-3865 2710);
DISPLAY 0.489362 (-3865 2710);
PAINT MONO (-3865 2710);
FORCEPROP 0 LASTPIN (-3875 2650) $PN DE69
J 0
(-3865 2660);
DISPLAY 0.489362 (-3865 2660);
PAINT MONO (-3865 2660);
FORCEPROP 0 LASTPIN (-3875 2600) $PN DE71
J 0
(-3865 2610);
DISPLAY 0.489362 (-3865 2610);
PAINT MONO (-3865 2610);
FORCEPROP 0 LASTPIN (-3875 2550) $PN DF69
J 0
(-3865 2560);
DISPLAY 0.489362 (-3865 2560);
PAINT MONO (-3865 2560);
FORCEPROP 0 LASTPIN (-5475 5000) $PN CD70
J 2
(-5485 5010);
DISPLAY 0.489362 (-5485 5010);
PAINT MONO (-5485 5010);
FORCEPROP 0 LASTPIN (-5475 4900) $PN CK70
J 2
(-5485 4910);
DISPLAY 0.489362 (-5485 4910);
PAINT MONO (-5485 4910);
FORCEPROP 0 LASTPIN (-5475 4800) $PN CT70
J 2
(-5485 4810);
DISPLAY 0.489362 (-5485 4810);
PAINT MONO (-5485 4810);
FORCEPROP 0 LASTPIN (-5475 4700) $PN DB70
J 2
(-5485 4710);
DISPLAY 0.489362 (-5485 4710);
PAINT MONO (-5485 4710);
FORCEPROP 0 LASTPIN (-5475 4600) $PN BY69
J 2
(-5485 4610);
DISPLAY 0.489362 (-5485 4610);
PAINT MONO (-5485 4610);
FORCEPROP 0 LASTPIN (-5475 4500) $PN CF69
J 2
(-5485 4510);
DISPLAY 0.489362 (-5485 4510);
PAINT MONO (-5485 4510);
FORCEPROP 0 LASTPIN (-5475 4400) $PN CM69
J 2
(-5485 4410);
DISPLAY 0.489362 (-5485 4410);
PAINT MONO (-5485 4410);
FORCEPROP 0 LASTPIN (-5475 4300) $PN CV69
J 2
(-5485 4310);
DISPLAY 0.489362 (-5485 4310);
PAINT MONO (-5485 4310);
FORCEPROP 0 LASTPIN (-5475 4200) $PN DD69
J 2
(-5485 4210);
DISPLAY 0.489362 (-5485 4210);
PAINT MONO (-5485 4210);
FORCEPROP 0 LASTPIN (-5475 4100) $PN BV70
J 2
(-5485 4110);
DISPLAY 0.489362 (-5485 4110);
PAINT MONO (-5485 4110);
FORCEPROP 0 LASTPIN (-5475 4950) $PN CE71
J 2
(-5485 4960);
DISPLAY 0.489362 (-5485 4960);
PAINT MONO (-5485 4960);
FORCEPROP 0 LASTPIN (-5475 4850) $PN CL71
J 2
(-5485 4860);
DISPLAY 0.489362 (-5485 4860);
PAINT MONO (-5485 4860);
FORCEPROP 0 LASTPIN (-5475 4750) $PN CU71
J 2
(-5485 4760);
DISPLAY 0.489362 (-5485 4760);
PAINT MONO (-5485 4760);
FORCEPROP 0 LASTPIN (-5475 4650) $PN DC71
J 2
(-5485 4660);
DISPLAY 0.489362 (-5485 4660);
PAINT MONO (-5485 4660);
FORCEPROP 0 LASTPIN (-5475 4550) $PN BW69
J 2
(-5485 4560);
DISPLAY 0.489362 (-5485 4560);
PAINT MONO (-5485 4560);
FORCEPROP 0 LASTPIN (-5475 4450) $PN CE69
J 2
(-5485 4460);
DISPLAY 0.489362 (-5485 4460);
PAINT MONO (-5485 4460);
FORCEPROP 0 LASTPIN (-5475 4350) $PN CL69
J 2
(-5485 4360);
DISPLAY 0.489362 (-5485 4360);
PAINT MONO (-5485 4360);
FORCEPROP 0 LASTPIN (-5475 4250) $PN CU69
J 2
(-5485 4260);
DISPLAY 0.489362 (-5485 4260);
PAINT MONO (-5485 4260);
FORCEPROP 0 LASTPIN (-5475 4150) $PN DC69
J 2
(-5485 4160);
DISPLAY 0.489362 (-5485 4160);
PAINT MONO (-5485 4160);
FORCEPROP 0 LASTPIN (-5475 4050) $PN BW71
J 2
(-5485 4060);
DISPLAY 0.489362 (-5485 4060);
PAINT MONO (-5485 4060);
FORCEPROP 0 LASTPIN (-5475 2300) $PN BL71
J 2
(-5485 2310);
DISPLAY 0.489362 (-5485 2310);
PAINT MONO (-5485 2310);
FORCEPROP 0 LASTPIN (-5475 1250) $PN BF69
J 2
(-5485 1260);
DISPLAY 0.489362 (-5485 1260);
PAINT MONO (-5485 1260);
FORCEPROP 2 LAST VALUE SOCKET6096_13568-001
J 0
(-5325 6330);
DISPLAY 0.489362 (-5325 6330);
PAINT SKYBLUE (-5325 6330);
FORCEPROP 1 LAST MATERIAL IO
J 0
(-5320 6232);
DISPLAY 0.489362 (-5320 6232);
PAINT SKYBLUE (-5320 6232);
FORCEPROP 2 LAST PART_TYPE SMLF
J 0
(-5325 6430);
DISPLAY 1.021277 (-5325 6430);
FORCEPROP 1 LAST NEEDS_NO_SIZE TRUE
J 0
(-4675 3675);
DISPLAY 0.723404 (-4675 3675);
PAINT GREEN (-4675 3675);
DISPLAY INVISIBLE (-4675 3675);
FORCEPROP 1 LAST CDS_LMAN_SYM_OUTLINE -650,2525,650,-2525
J 0
(-4675 3675);
DISPLAY 0.468085 (-4675 3675);
PAINT GREEN (-4675 3675);
DISPLAY INVISIBLE (-4675 3675);
FORCEPROP 2 LAST CDS_LIB pure_quanta
J 0
(-4675 3675);
DISPLAY INVISIBLE (-4675 3675);
FORCEPROP 1 LAST PATH I159
J 0
(-4675 3675);
DISPLAY 0.723404 (-4675 3675);
PAINT GREEN (-4675 3675);
DISPLAY INVISIBLE (-4675 3675);
FORCEPROP 1 LAST PART_NUMBER DGA^6000030
J 0
(-5320 6359);
DISPLAY 0.489362 (-5320 6359);
PAINT SKYBLUE (-5320 6359);
DISPLAY INVISIBLE (-5320 6359);
FORCEADD OFFPAGE..3
(-2675 6075);
FORCEPROP 2 LAST $XR0 90 
J 0
(-2461 6075);
DISPLAY 0.638298 (-2461 6075);
PAINT MONO (-2461 6075);
FORCEPROP 2 LAST CDS_LIB mstr_standard
J 0
(-2675 6075);
DISPLAY 0.723404 (-2675 6075);
PAINT MONO (-2675 6075);
DISPLAY INVISIBLE (-2675 6075);
FORCEPROP 1 LAST OFFPAGE TRUE
J 0
(-2350 5950);
DISPLAY 0.872340 (-2350 5950);
PAINT GREEN (-2350 5950);
DISPLAY INVISIBLE (-2350 5950);
FORCEPROP 1 LAST COMMENT_BODY TRUE
J 0
(-2725 5975);
DISPLAY 0.872340 (-2725 5975);
PAINT GREEN (-2725 5975);
DISPLAY INVISIBLE (-2725 5975);
FORCEPROP 2 LAST PATH I160
J 0
(-2450 6125);
DISPLAY 1.021277 (-2450 6125);
DISPLAY INVISIBLE (-2450 6125);
FORCEADD OFFPAGE..3
(-2675 4275);
FORCEPROP 2 LAST $XR0 90 
J 0
(-2461 4275);
DISPLAY 0.638298 (-2461 4275);
PAINT MONO (-2461 4275);
FORCEPROP 2 LAST CDS_LIB mstr_standard
J 0
(-2675 4275);
DISPLAY 0.723404 (-2675 4275);
PAINT MONO (-2675 4275);
DISPLAY INVISIBLE (-2675 4275);
FORCEPROP 1 LAST OFFPAGE TRUE
J 0
(-2350 4150);
DISPLAY 0.872340 (-2350 4150);
PAINT GREEN (-2350 4150);
DISPLAY INVISIBLE (-2350 4150);
FORCEPROP 1 LAST COMMENT_BODY TRUE
J 0
(-2725 4175);
DISPLAY 0.872340 (-2725 4175);
PAINT GREEN (-2725 4175);
DISPLAY INVISIBLE (-2725 4175);
FORCEPROP 2 LAST PATH I161
J 0
(-2450 4325);
DISPLAY 1.021277 (-2450 4325);
DISPLAY INVISIBLE (-2450 4325);
FORCEADD TAP..1
(-3400 6050);
FORCEPROP 3 LASTPIN (-3450 6050) SIG_NAME M_E_CPU0_SA_DQ<0>
J 0
(-3440 6060);
DISPLAY 0.659574 (-3440 6060);
PAINT MONO (-3440 6060);
DISPLAY INVISIBLE (-3440 6060);
FORCEPROP 1 LASTPIN (-3450 6050) BN 0
J 0
(-3462 6058);
DISPLAY 0.489362 (-3462 6058);
PAINT GREEN (-3462 6058);
FORCEPROP 2 LAST CDS_LIB mstr_standard
J 0
(-3400 6050);
DISPLAY 0.723404 (-3400 6050);
PAINT MONO (-3400 6050);
DISPLAY INVISIBLE (-3400 6050);
FORCEPROP 1 LAST BODY_TYPE PLUMBING
J 0
(-3400 6100);
DISPLAY 0.872340 (-3400 6100);
PAINT GREEN (-3400 6100);
DISPLAY INVISIBLE (-3400 6100);
FORCEPROP 1 LAST HDL_TAP TRUE
J 0
(-3075 5925);
DISPLAY 0.872340 (-3075 5925);
DISPLAY INVISIBLE (-3075 5925);
FORCEPROP 1 LAST PATH I162
J 0
(-3402 6050);
DISPLAY 0.872340 (-3402 6050);
PAINT GREEN (-3402 6050);
DISPLAY INVISIBLE (-3402 6050);
FORCEADD TAP..1
(-3400 5900);
FORCEPROP 3 LASTPIN (-3450 5900) SIG_NAME M_E_CPU0_SA_DQ<3>
J 0
(-3440 5910);
DISPLAY 0.659574 (-3440 5910);
PAINT MONO (-3440 5910);
DISPLAY INVISIBLE (-3440 5910);
FORCEPROP 1 LASTPIN (-3450 5900) BN 3
J 0
(-3462 5908);
DISPLAY 0.489362 (-3462 5908);
PAINT GREEN (-3462 5908);
FORCEPROP 2 LAST CDS_LIB mstr_standard
J 0
(-3400 5900);
DISPLAY 0.723404 (-3400 5900);
PAINT MONO (-3400 5900);
DISPLAY INVISIBLE (-3400 5900);
FORCEPROP 1 LAST BODY_TYPE PLUMBING
J 0
(-3400 5950);
DISPLAY 0.872340 (-3400 5950);
PAINT GREEN (-3400 5950);
DISPLAY INVISIBLE (-3400 5950);
FORCEPROP 1 LAST HDL_TAP TRUE
J 0
(-3075 5775);
DISPLAY 0.872340 (-3075 5775);
DISPLAY INVISIBLE (-3075 5775);
FORCEPROP 1 LAST PATH I163
J 0
(-3402 5900);
DISPLAY 0.872340 (-3402 5900);
PAINT GREEN (-3402 5900);
DISPLAY INVISIBLE (-3402 5900);
FORCEADD TAP..1
(-3400 6000);
FORCEPROP 3 LASTPIN (-3450 6000) SIG_NAME M_E_CPU0_SA_DQ<1>
J 0
(-3440 6010);
DISPLAY 0.659574 (-3440 6010);
PAINT MONO (-3440 6010);
DISPLAY INVISIBLE (-3440 6010);
FORCEPROP 1 LASTPIN (-3450 6000) BN 1
J 0
(-3462 6008);
DISPLAY 0.489362 (-3462 6008);
PAINT GREEN (-3462 6008);
FORCEPROP 2 LAST CDS_LIB mstr_standard
J 0
(-3400 6000);
DISPLAY 0.723404 (-3400 6000);
PAINT MONO (-3400 6000);
DISPLAY INVISIBLE (-3400 6000);
FORCEPROP 1 LAST BODY_TYPE PLUMBING
J 0
(-3400 6050);
DISPLAY 0.872340 (-3400 6050);
PAINT GREEN (-3400 6050);
DISPLAY INVISIBLE (-3400 6050);
FORCEPROP 1 LAST HDL_TAP TRUE
J 0
(-3075 5875);
DISPLAY 0.872340 (-3075 5875);
DISPLAY INVISIBLE (-3075 5875);
FORCEPROP 1 LAST PATH I164
J 0
(-3402 6000);
DISPLAY 0.872340 (-3402 6000);
PAINT GREEN (-3402 6000);
DISPLAY INVISIBLE (-3402 6000);
FORCEADD TAP..1
(-3400 5950);
FORCEPROP 3 LASTPIN (-3450 5950) SIG_NAME M_E_CPU0_SA_DQ<2>
J 0
(-3440 5960);
DISPLAY 0.659574 (-3440 5960);
PAINT MONO (-3440 5960);
DISPLAY INVISIBLE (-3440 5960);
FORCEPROP 1 LASTPIN (-3450 5950) BN 2
J 0
(-3462 5958);
DISPLAY 0.489362 (-3462 5958);
PAINT GREEN (-3462 5958);
FORCEPROP 2 LAST CDS_LIB mstr_standard
J 0
(-3400 5950);
DISPLAY 0.723404 (-3400 5950);
PAINT MONO (-3400 5950);
DISPLAY INVISIBLE (-3400 5950);
FORCEPROP 1 LAST BODY_TYPE PLUMBING
J 0
(-3400 6000);
DISPLAY 0.872340 (-3400 6000);
PAINT GREEN (-3400 6000);
DISPLAY INVISIBLE (-3400 6000);
FORCEPROP 1 LAST HDL_TAP TRUE
J 0
(-3075 5825);
DISPLAY 0.872340 (-3075 5825);
DISPLAY INVISIBLE (-3075 5825);
FORCEPROP 1 LAST PATH I165
J 0
(-3402 5950);
DISPLAY 0.872340 (-3402 5950);
PAINT GREEN (-3402 5950);
DISPLAY INVISIBLE (-3402 5950);
FORCEADD TAP..1
(-3400 5800);
FORCEPROP 3 LASTPIN (-3450 5800) SIG_NAME M_E_CPU0_SA_DQ<5>
J 0
(-3440 5810);
DISPLAY 0.659574 (-3440 5810);
PAINT MONO (-3440 5810);
DISPLAY INVISIBLE (-3440 5810);
FORCEPROP 1 LASTPIN (-3450 5800) BN 5
J 0
(-3462 5808);
DISPLAY 0.489362 (-3462 5808);
PAINT GREEN (-3462 5808);
FORCEPROP 2 LAST CDS_LIB mstr_standard
J 0
(-3400 5800);
DISPLAY 0.723404 (-3400 5800);
PAINT MONO (-3400 5800);
DISPLAY INVISIBLE (-3400 5800);
FORCEPROP 1 LAST BODY_TYPE PLUMBING
J 0
(-3400 5850);
DISPLAY 0.872340 (-3400 5850);
PAINT GREEN (-3400 5850);
DISPLAY INVISIBLE (-3400 5850);
FORCEPROP 1 LAST HDL_TAP TRUE
J 0
(-3075 5675);
DISPLAY 0.872340 (-3075 5675);
DISPLAY INVISIBLE (-3075 5675);
FORCEPROP 1 LAST PATH I166
J 0
(-3402 5800);
DISPLAY 0.872340 (-3402 5800);
PAINT GREEN (-3402 5800);
DISPLAY INVISIBLE (-3402 5800);
FORCEADD TAP..1
(-3400 5850);
FORCEPROP 3 LASTPIN (-3450 5850) SIG_NAME M_E_CPU0_SA_DQ<4>
J 0
(-3440 5860);
DISPLAY 0.659574 (-3440 5860);
PAINT MONO (-3440 5860);
DISPLAY INVISIBLE (-3440 5860);
FORCEPROP 1 LASTPIN (-3450 5850) BN 4
J 0
(-3462 5858);
DISPLAY 0.489362 (-3462 5858);
PAINT GREEN (-3462 5858);
FORCEPROP 2 LAST CDS_LIB mstr_standard
J 0
(-3400 5850);
DISPLAY 0.723404 (-3400 5850);
PAINT MONO (-3400 5850);
DISPLAY INVISIBLE (-3400 5850);
FORCEPROP 1 LAST BODY_TYPE PLUMBING
J 0
(-3400 5900);
DISPLAY 0.872340 (-3400 5900);
PAINT GREEN (-3400 5900);
DISPLAY INVISIBLE (-3400 5900);
FORCEPROP 1 LAST HDL_TAP TRUE
J 0
(-3075 5725);
DISPLAY 0.872340 (-3075 5725);
DISPLAY INVISIBLE (-3075 5725);
FORCEPROP 1 LAST PATH I167
J 0
(-3402 5850);
DISPLAY 0.872340 (-3402 5850);
PAINT GREEN (-3402 5850);
DISPLAY INVISIBLE (-3402 5850);
FORCEADD TAP..1
(-3400 5750);
FORCEPROP 3 LASTPIN (-3450 5750) SIG_NAME M_E_CPU0_SA_DQ<6>
J 0
(-3440 5760);
DISPLAY 0.659574 (-3440 5760);
PAINT MONO (-3440 5760);
DISPLAY INVISIBLE (-3440 5760);
FORCEPROP 1 LASTPIN (-3450 5750) BN 6
J 0
(-3462 5758);
DISPLAY 0.489362 (-3462 5758);
PAINT GREEN (-3462 5758);
FORCEPROP 2 LAST CDS_LIB mstr_standard
J 0
(-3400 5750);
DISPLAY 0.723404 (-3400 5750);
PAINT MONO (-3400 5750);
DISPLAY INVISIBLE (-3400 5750);
FORCEPROP 1 LAST BODY_TYPE PLUMBING
J 0
(-3400 5800);
DISPLAY 0.872340 (-3400 5800);
PAINT GREEN (-3400 5800);
DISPLAY INVISIBLE (-3400 5800);
FORCEPROP 1 LAST HDL_TAP TRUE
J 0
(-3075 5625);
DISPLAY 0.872340 (-3075 5625);
DISPLAY INVISIBLE (-3075 5625);
FORCEPROP 1 LAST PATH I168
J 0
(-3402 5750);
DISPLAY 0.872340 (-3402 5750);
PAINT GREEN (-3402 5750);
DISPLAY INVISIBLE (-3402 5750);
FORCEADD TAP..1
(-3400 5700);
FORCEPROP 3 LASTPIN (-3450 5700) SIG_NAME M_E_CPU0_SA_DQ<7>
J 0
(-3440 5710);
DISPLAY 0.659574 (-3440 5710);
PAINT MONO (-3440 5710);
DISPLAY INVISIBLE (-3440 5710);
FORCEPROP 1 LASTPIN (-3450 5700) BN 7
J 0
(-3462 5708);
DISPLAY 0.489362 (-3462 5708);
PAINT GREEN (-3462 5708);
FORCEPROP 2 LAST CDS_LIB mstr_standard
J 0
(-3400 5700);
DISPLAY 0.723404 (-3400 5700);
PAINT MONO (-3400 5700);
DISPLAY INVISIBLE (-3400 5700);
FORCEPROP 1 LAST BODY_TYPE PLUMBING
J 0
(-3400 5750);
DISPLAY 0.872340 (-3400 5750);
PAINT GREEN (-3400 5750);
DISPLAY INVISIBLE (-3400 5750);
FORCEPROP 1 LAST HDL_TAP TRUE
J 0
(-3075 5575);
DISPLAY 0.872340 (-3075 5575);
DISPLAY INVISIBLE (-3075 5575);
FORCEPROP 1 LAST PATH I169
J 0
(-3402 5700);
DISPLAY 0.872340 (-3402 5700);
PAINT GREEN (-3402 5700);
DISPLAY INVISIBLE (-3402 5700);
FORCEADD TAP..1
(-3400 5550);
FORCEPROP 3 LASTPIN (-3450 5550) SIG_NAME M_E_CPU0_SA_DQ<9>
J 0
(-3440 5560);
DISPLAY 0.659574 (-3440 5560);
PAINT MONO (-3440 5560);
DISPLAY INVISIBLE (-3440 5560);
FORCEPROP 1 LASTPIN (-3450 5550) BN 9
J 0
(-3462 5558);
DISPLAY 0.489362 (-3462 5558);
PAINT GREEN (-3462 5558);
FORCEPROP 2 LAST CDS_LIB mstr_standard
J 0
(-3400 5550);
DISPLAY 0.723404 (-3400 5550);
PAINT MONO (-3400 5550);
DISPLAY INVISIBLE (-3400 5550);
FORCEPROP 1 LAST BODY_TYPE PLUMBING
J 0
(-3400 5600);
DISPLAY 0.872340 (-3400 5600);
PAINT GREEN (-3400 5600);
DISPLAY INVISIBLE (-3400 5600);
FORCEPROP 1 LAST HDL_TAP TRUE
J 0
(-3075 5425);
DISPLAY 0.872340 (-3075 5425);
DISPLAY INVISIBLE (-3075 5425);
FORCEPROP 1 LAST PATH I170
J 0
(-3402 5550);
DISPLAY 0.872340 (-3402 5550);
PAINT GREEN (-3402 5550);
DISPLAY INVISIBLE (-3402 5550);
FORCEADD TAP..1
(-3400 5600);
FORCEPROP 3 LASTPIN (-3450 5600) SIG_NAME M_E_CPU0_SA_DQ<8>
J 0
(-3440 5610);
DISPLAY 0.659574 (-3440 5610);
PAINT MONO (-3440 5610);
DISPLAY INVISIBLE (-3440 5610);
FORCEPROP 1 LASTPIN (-3450 5600) BN 8
J 0
(-3462 5608);
DISPLAY 0.489362 (-3462 5608);
PAINT GREEN (-3462 5608);
FORCEPROP 2 LAST CDS_LIB mstr_standard
J 0
(-3400 5600);
DISPLAY 0.723404 (-3400 5600);
PAINT MONO (-3400 5600);
DISPLAY INVISIBLE (-3400 5600);
FORCEPROP 1 LAST BODY_TYPE PLUMBING
J 0
(-3400 5650);
DISPLAY 0.872340 (-3400 5650);
PAINT GREEN (-3400 5650);
DISPLAY INVISIBLE (-3400 5650);
FORCEPROP 1 LAST HDL_TAP TRUE
J 0
(-3075 5475);
DISPLAY 0.872340 (-3075 5475);
DISPLAY INVISIBLE (-3075 5475);
FORCEPROP 1 LAST PATH I171
J 0
(-3402 5600);
DISPLAY 0.872340 (-3402 5600);
PAINT GREEN (-3402 5600);
DISPLAY INVISIBLE (-3402 5600);
FORCEADD TAP..1
(-3400 5400);
FORCEPROP 3 LASTPIN (-3450 5400) SIG_NAME M_E_CPU0_SA_DQ<12>
J 0
(-3440 5410);
DISPLAY 0.659574 (-3440 5410);
PAINT MONO (-3440 5410);
DISPLAY INVISIBLE (-3440 5410);
FORCEPROP 1 LASTPIN (-3450 5400) BN 12
J 0
(-3462 5408);
DISPLAY 0.489362 (-3462 5408);
PAINT GREEN (-3462 5408);
FORCEPROP 2 LAST CDS_LIB mstr_standard
J 0
(-3400 5400);
DISPLAY 0.723404 (-3400 5400);
PAINT MONO (-3400 5400);
DISPLAY INVISIBLE (-3400 5400);
FORCEPROP 1 LAST BODY_TYPE PLUMBING
J 0
(-3400 5450);
DISPLAY 0.872340 (-3400 5450);
PAINT GREEN (-3400 5450);
DISPLAY INVISIBLE (-3400 5450);
FORCEPROP 1 LAST HDL_TAP TRUE
J 0
(-3075 5275);
DISPLAY 0.872340 (-3075 5275);
DISPLAY INVISIBLE (-3075 5275);
FORCEPROP 1 LAST PATH I172
J 0
(-3402 5400);
DISPLAY 0.872340 (-3402 5400);
PAINT GREEN (-3402 5400);
DISPLAY INVISIBLE (-3402 5400);
FORCEADD TAP..1
(-3400 5450);
FORCEPROP 3 LASTPIN (-3450 5450) SIG_NAME M_E_CPU0_SA_DQ<11>
J 0
(-3440 5460);
DISPLAY 0.659574 (-3440 5460);
PAINT MONO (-3440 5460);
DISPLAY INVISIBLE (-3440 5460);
FORCEPROP 1 LASTPIN (-3450 5450) BN 11
J 0
(-3462 5458);
DISPLAY 0.489362 (-3462 5458);
PAINT GREEN (-3462 5458);
FORCEPROP 2 LAST CDS_LIB mstr_standard
J 0
(-3400 5450);
DISPLAY 0.723404 (-3400 5450);
PAINT MONO (-3400 5450);
DISPLAY INVISIBLE (-3400 5450);
FORCEPROP 1 LAST BODY_TYPE PLUMBING
J 0
(-3400 5500);
DISPLAY 0.872340 (-3400 5500);
PAINT GREEN (-3400 5500);
DISPLAY INVISIBLE (-3400 5500);
FORCEPROP 1 LAST HDL_TAP TRUE
J 0
(-3075 5325);
DISPLAY 0.872340 (-3075 5325);
DISPLAY INVISIBLE (-3075 5325);
FORCEPROP 1 LAST PATH I173
J 0
(-3402 5450);
DISPLAY 0.872340 (-3402 5450);
PAINT GREEN (-3402 5450);
DISPLAY INVISIBLE (-3402 5450);
FORCEADD TAP..1
(-3400 5500);
FORCEPROP 3 LASTPIN (-3450 5500) SIG_NAME M_E_CPU0_SA_DQ<10>
J 0
(-3440 5510);
DISPLAY 0.659574 (-3440 5510);
PAINT MONO (-3440 5510);
DISPLAY INVISIBLE (-3440 5510);
FORCEPROP 1 LASTPIN (-3450 5500) BN 10
J 0
(-3462 5508);
DISPLAY 0.489362 (-3462 5508);
PAINT GREEN (-3462 5508);
FORCEPROP 2 LAST CDS_LIB mstr_standard
J 0
(-3400 5500);
DISPLAY 0.723404 (-3400 5500);
PAINT MONO (-3400 5500);
DISPLAY INVISIBLE (-3400 5500);
FORCEPROP 1 LAST BODY_TYPE PLUMBING
J 0
(-3400 5550);
DISPLAY 0.872340 (-3400 5550);
PAINT GREEN (-3400 5550);
DISPLAY INVISIBLE (-3400 5550);
FORCEPROP 1 LAST HDL_TAP TRUE
J 0
(-3075 5375);
DISPLAY 0.872340 (-3075 5375);
DISPLAY INVISIBLE (-3075 5375);
FORCEPROP 1 LAST PATH I174
J 0
(-3402 5500);
DISPLAY 0.872340 (-3402 5500);
PAINT GREEN (-3402 5500);
DISPLAY INVISIBLE (-3402 5500);
FORCEADD TAP..1
(-3400 5250);
FORCEPROP 3 LASTPIN (-3450 5250) SIG_NAME M_E_CPU0_SA_DQ<15>
J 0
(-3440 5260);
DISPLAY 0.659574 (-3440 5260);
PAINT MONO (-3440 5260);
DISPLAY INVISIBLE (-3440 5260);
FORCEPROP 1 LASTPIN (-3450 5250) BN 15
J 0
(-3462 5258);
DISPLAY 0.489362 (-3462 5258);
PAINT GREEN (-3462 5258);
FORCEPROP 2 LAST CDS_LIB mstr_standard
J 0
(-3400 5250);
DISPLAY 0.723404 (-3400 5250);
PAINT MONO (-3400 5250);
DISPLAY INVISIBLE (-3400 5250);
FORCEPROP 1 LAST BODY_TYPE PLUMBING
J 0
(-3400 5300);
DISPLAY 0.872340 (-3400 5300);
PAINT GREEN (-3400 5300);
DISPLAY INVISIBLE (-3400 5300);
FORCEPROP 1 LAST HDL_TAP TRUE
J 0
(-3075 5125);
DISPLAY 0.872340 (-3075 5125);
DISPLAY INVISIBLE (-3075 5125);
FORCEPROP 1 LAST PATH I175
J 0
(-3402 5250);
DISPLAY 0.872340 (-3402 5250);
PAINT GREEN (-3402 5250);
DISPLAY INVISIBLE (-3402 5250);
FORCEADD TAP..1
(-3400 5300);
FORCEPROP 3 LASTPIN (-3450 5300) SIG_NAME M_E_CPU0_SA_DQ<14>
J 0
(-3440 5310);
DISPLAY 0.659574 (-3440 5310);
PAINT MONO (-3440 5310);
DISPLAY INVISIBLE (-3440 5310);
FORCEPROP 1 LASTPIN (-3450 5300) BN 14
J 0
(-3462 5308);
DISPLAY 0.489362 (-3462 5308);
PAINT GREEN (-3462 5308);
FORCEPROP 2 LAST CDS_LIB mstr_standard
J 0
(-3400 5300);
DISPLAY 0.723404 (-3400 5300);
PAINT MONO (-3400 5300);
DISPLAY INVISIBLE (-3400 5300);
FORCEPROP 1 LAST BODY_TYPE PLUMBING
J 0
(-3400 5350);
DISPLAY 0.872340 (-3400 5350);
PAINT GREEN (-3400 5350);
DISPLAY INVISIBLE (-3400 5350);
FORCEPROP 1 LAST HDL_TAP TRUE
J 0
(-3075 5175);
DISPLAY 0.872340 (-3075 5175);
DISPLAY INVISIBLE (-3075 5175);
FORCEPROP 1 LAST PATH I176
J 0
(-3402 5300);
DISPLAY 0.872340 (-3402 5300);
PAINT GREEN (-3402 5300);
DISPLAY INVISIBLE (-3402 5300);
FORCEADD TAP..1
(-3400 5350);
FORCEPROP 3 LASTPIN (-3450 5350) SIG_NAME M_E_CPU0_SA_DQ<13>
J 0
(-3440 5360);
DISPLAY 0.659574 (-3440 5360);
PAINT MONO (-3440 5360);
DISPLAY INVISIBLE (-3440 5360);
FORCEPROP 1 LASTPIN (-3450 5350) BN 13
J 0
(-3462 5358);
DISPLAY 0.489362 (-3462 5358);
PAINT GREEN (-3462 5358);
FORCEPROP 2 LAST CDS_LIB mstr_standard
J 0
(-3400 5350);
DISPLAY 0.723404 (-3400 5350);
PAINT MONO (-3400 5350);
DISPLAY INVISIBLE (-3400 5350);
FORCEPROP 1 LAST BODY_TYPE PLUMBING
J 0
(-3400 5400);
DISPLAY 0.872340 (-3400 5400);
PAINT GREEN (-3400 5400);
DISPLAY INVISIBLE (-3400 5400);
FORCEPROP 1 LAST HDL_TAP TRUE
J 0
(-3075 5225);
DISPLAY 0.872340 (-3075 5225);
DISPLAY INVISIBLE (-3075 5225);
FORCEPROP 1 LAST PATH I177
J 0
(-3402 5350);
DISPLAY 0.872340 (-3402 5350);
PAINT GREEN (-3402 5350);
DISPLAY INVISIBLE (-3402 5350);
FORCEADD TAP..1
(-3400 5150);
FORCEPROP 3 LASTPIN (-3450 5150) SIG_NAME M_E_CPU0_SA_DQ<16>
J 0
(-3440 5160);
DISPLAY 0.659574 (-3440 5160);
PAINT MONO (-3440 5160);
DISPLAY INVISIBLE (-3440 5160);
FORCEPROP 1 LASTPIN (-3450 5150) BN 16
J 0
(-3462 5158);
DISPLAY 0.489362 (-3462 5158);
PAINT GREEN (-3462 5158);
FORCEPROP 2 LAST CDS_LIB mstr_standard
J 0
(-3400 5150);
DISPLAY 0.723404 (-3400 5150);
PAINT MONO (-3400 5150);
DISPLAY INVISIBLE (-3400 5150);
FORCEPROP 1 LAST BODY_TYPE PLUMBING
J 0
(-3400 5200);
DISPLAY 0.872340 (-3400 5200);
PAINT GREEN (-3400 5200);
DISPLAY INVISIBLE (-3400 5200);
FORCEPROP 1 LAST HDL_TAP TRUE
J 0
(-3075 5025);
DISPLAY 0.872340 (-3075 5025);
DISPLAY INVISIBLE (-3075 5025);
FORCEPROP 1 LAST PATH I178
J 0
(-3402 5150);
DISPLAY 0.872340 (-3402 5150);
PAINT GREEN (-3402 5150);
DISPLAY INVISIBLE (-3402 5150);
FORCEADD TAP..1
(-3400 5050);
FORCEPROP 3 LASTPIN (-3450 5050) SIG_NAME M_E_CPU0_SA_DQ<18>
J 0
(-3440 5060);
DISPLAY 0.659574 (-3440 5060);
PAINT MONO (-3440 5060);
DISPLAY INVISIBLE (-3440 5060);
FORCEPROP 1 LASTPIN (-3450 5050) BN 18
J 0
(-3462 5058);
DISPLAY 0.489362 (-3462 5058);
PAINT GREEN (-3462 5058);
FORCEPROP 2 LAST CDS_LIB mstr_standard
J 0
(-3400 5050);
DISPLAY 0.723404 (-3400 5050);
PAINT MONO (-3400 5050);
DISPLAY INVISIBLE (-3400 5050);
FORCEPROP 1 LAST BODY_TYPE PLUMBING
J 0
(-3400 5100);
DISPLAY 0.872340 (-3400 5100);
PAINT GREEN (-3400 5100);
DISPLAY INVISIBLE (-3400 5100);
FORCEPROP 1 LAST HDL_TAP TRUE
J 0
(-3075 4925);
DISPLAY 0.872340 (-3075 4925);
DISPLAY INVISIBLE (-3075 4925);
FORCEPROP 1 LAST PATH I179
J 0
(-3402 5050);
DISPLAY 0.872340 (-3402 5050);
PAINT GREEN (-3402 5050);
DISPLAY INVISIBLE (-3402 5050);
FORCEADD TAP..1
(-3400 5100);
FORCEPROP 3 LASTPIN (-3450 5100) SIG_NAME M_E_CPU0_SA_DQ<17>
J 0
(-3440 5110);
DISPLAY 0.659574 (-3440 5110);
PAINT MONO (-3440 5110);
DISPLAY INVISIBLE (-3440 5110);
FORCEPROP 1 LASTPIN (-3450 5100) BN 17
J 0
(-3462 5108);
DISPLAY 0.489362 (-3462 5108);
PAINT GREEN (-3462 5108);
FORCEPROP 2 LAST CDS_LIB mstr_standard
J 0
(-3400 5100);
DISPLAY 0.723404 (-3400 5100);
PAINT MONO (-3400 5100);
DISPLAY INVISIBLE (-3400 5100);
FORCEPROP 1 LAST BODY_TYPE PLUMBING
J 0
(-3400 5150);
DISPLAY 0.872340 (-3400 5150);
PAINT GREEN (-3400 5150);
DISPLAY INVISIBLE (-3400 5150);
FORCEPROP 1 LAST HDL_TAP TRUE
J 0
(-3075 4975);
DISPLAY 0.872340 (-3075 4975);
DISPLAY INVISIBLE (-3075 4975);
FORCEPROP 1 LAST PATH I180
J 0
(-3402 5100);
DISPLAY 0.872340 (-3402 5100);
PAINT GREEN (-3402 5100);
DISPLAY INVISIBLE (-3402 5100);
FORCEADD TAP..1
(-3400 5000);
FORCEPROP 3 LASTPIN (-3450 5000) SIG_NAME M_E_CPU0_SA_DQ<19>
J 0
(-3440 5010);
DISPLAY 0.659574 (-3440 5010);
PAINT MONO (-3440 5010);
DISPLAY INVISIBLE (-3440 5010);
FORCEPROP 1 LASTPIN (-3450 5000) BN 19
J 0
(-3462 5008);
DISPLAY 0.489362 (-3462 5008);
PAINT GREEN (-3462 5008);
FORCEPROP 2 LAST CDS_LIB mstr_standard
J 0
(-3400 5000);
DISPLAY 0.723404 (-3400 5000);
PAINT MONO (-3400 5000);
DISPLAY INVISIBLE (-3400 5000);
FORCEPROP 1 LAST BODY_TYPE PLUMBING
J 0
(-3400 5050);
DISPLAY 0.872340 (-3400 5050);
PAINT GREEN (-3400 5050);
DISPLAY INVISIBLE (-3400 5050);
FORCEPROP 1 LAST HDL_TAP TRUE
J 0
(-3075 4875);
DISPLAY 0.872340 (-3075 4875);
DISPLAY INVISIBLE (-3075 4875);
FORCEPROP 1 LAST PATH I181
J 0
(-3402 5000);
DISPLAY 0.872340 (-3402 5000);
PAINT GREEN (-3402 5000);
DISPLAY INVISIBLE (-3402 5000);
FORCEADD TAP..1
(-3400 4950);
FORCEPROP 3 LASTPIN (-3450 4950) SIG_NAME M_E_CPU0_SA_DQ<20>
J 0
(-3440 4960);
DISPLAY 0.659574 (-3440 4960);
PAINT MONO (-3440 4960);
DISPLAY INVISIBLE (-3440 4960);
FORCEPROP 1 LASTPIN (-3450 4950) BN 20
J 0
(-3462 4958);
DISPLAY 0.489362 (-3462 4958);
PAINT GREEN (-3462 4958);
FORCEPROP 2 LAST CDS_LIB mstr_standard
J 0
(-3400 4950);
DISPLAY 0.723404 (-3400 4950);
PAINT MONO (-3400 4950);
DISPLAY INVISIBLE (-3400 4950);
FORCEPROP 1 LAST BODY_TYPE PLUMBING
J 0
(-3400 5000);
DISPLAY 0.872340 (-3400 5000);
PAINT GREEN (-3400 5000);
DISPLAY INVISIBLE (-3400 5000);
FORCEPROP 1 LAST HDL_TAP TRUE
J 0
(-3075 4825);
DISPLAY 0.872340 (-3075 4825);
DISPLAY INVISIBLE (-3075 4825);
FORCEPROP 1 LAST PATH I182
J 0
(-3402 4950);
DISPLAY 0.872340 (-3402 4950);
PAINT GREEN (-3402 4950);
DISPLAY INVISIBLE (-3402 4950);
FORCEADD TAP..1
(-3400 4900);
FORCEPROP 3 LASTPIN (-3450 4900) SIG_NAME M_E_CPU0_SA_DQ<21>
J 0
(-3440 4910);
DISPLAY 0.659574 (-3440 4910);
PAINT MONO (-3440 4910);
DISPLAY INVISIBLE (-3440 4910);
FORCEPROP 1 LASTPIN (-3450 4900) BN 21
J 0
(-3462 4908);
DISPLAY 0.489362 (-3462 4908);
PAINT GREEN (-3462 4908);
FORCEPROP 2 LAST CDS_LIB mstr_standard
J 0
(-3400 4900);
DISPLAY 0.723404 (-3400 4900);
PAINT MONO (-3400 4900);
DISPLAY INVISIBLE (-3400 4900);
FORCEPROP 1 LAST BODY_TYPE PLUMBING
J 0
(-3400 4950);
DISPLAY 0.872340 (-3400 4950);
PAINT GREEN (-3400 4950);
DISPLAY INVISIBLE (-3400 4950);
FORCEPROP 1 LAST HDL_TAP TRUE
J 0
(-3075 4775);
DISPLAY 0.872340 (-3075 4775);
DISPLAY INVISIBLE (-3075 4775);
FORCEPROP 1 LAST PATH I183
J 0
(-3402 4900);
DISPLAY 0.872340 (-3402 4900);
PAINT GREEN (-3402 4900);
DISPLAY INVISIBLE (-3402 4900);
FORCEADD TAP..1
(-3400 4800);
FORCEPROP 3 LASTPIN (-3450 4800) SIG_NAME M_E_CPU0_SA_DQ<23>
J 0
(-3440 4810);
DISPLAY 0.659574 (-3440 4810);
PAINT MONO (-3440 4810);
DISPLAY INVISIBLE (-3440 4810);
FORCEPROP 1 LASTPIN (-3450 4800) BN 23
J 0
(-3462 4808);
DISPLAY 0.489362 (-3462 4808);
PAINT GREEN (-3462 4808);
FORCEPROP 2 LAST CDS_LIB mstr_standard
J 0
(-3400 4800);
DISPLAY 0.723404 (-3400 4800);
PAINT MONO (-3400 4800);
DISPLAY INVISIBLE (-3400 4800);
FORCEPROP 1 LAST BODY_TYPE PLUMBING
J 0
(-3400 4850);
DISPLAY 0.872340 (-3400 4850);
PAINT GREEN (-3400 4850);
DISPLAY INVISIBLE (-3400 4850);
FORCEPROP 1 LAST HDL_TAP TRUE
J 0
(-3075 4675);
DISPLAY 0.872340 (-3075 4675);
DISPLAY INVISIBLE (-3075 4675);
FORCEPROP 1 LAST PATH I184
J 0
(-3402 4800);
DISPLAY 0.872340 (-3402 4800);
PAINT GREEN (-3402 4800);
DISPLAY INVISIBLE (-3402 4800);
FORCEADD TAP..1
(-3400 4850);
FORCEPROP 3 LASTPIN (-3450 4850) SIG_NAME M_E_CPU0_SA_DQ<22>
J 0
(-3440 4860);
DISPLAY 0.659574 (-3440 4860);
PAINT MONO (-3440 4860);
DISPLAY INVISIBLE (-3440 4860);
FORCEPROP 1 LASTPIN (-3450 4850) BN 22
J 0
(-3462 4858);
DISPLAY 0.489362 (-3462 4858);
PAINT GREEN (-3462 4858);
FORCEPROP 2 LAST CDS_LIB mstr_standard
J 0
(-3400 4850);
DISPLAY 0.723404 (-3400 4850);
PAINT MONO (-3400 4850);
DISPLAY INVISIBLE (-3400 4850);
FORCEPROP 1 LAST BODY_TYPE PLUMBING
J 0
(-3400 4900);
DISPLAY 0.872340 (-3400 4900);
PAINT GREEN (-3400 4900);
DISPLAY INVISIBLE (-3400 4900);
FORCEPROP 1 LAST HDL_TAP TRUE
J 0
(-3075 4725);
DISPLAY 0.872340 (-3075 4725);
DISPLAY INVISIBLE (-3075 4725);
FORCEPROP 1 LAST PATH I185
J 0
(-3402 4850);
DISPLAY 0.872340 (-3402 4850);
PAINT GREEN (-3402 4850);
DISPLAY INVISIBLE (-3402 4850);
FORCEADD TAP..1
(-3400 4650);
FORCEPROP 3 LASTPIN (-3450 4650) SIG_NAME M_E_CPU0_SA_DQ<25>
J 0
(-3440 4660);
DISPLAY 0.659574 (-3440 4660);
PAINT MONO (-3440 4660);
DISPLAY INVISIBLE (-3440 4660);
FORCEPROP 1 LASTPIN (-3450 4650) BN 25
J 0
(-3462 4658);
DISPLAY 0.489362 (-3462 4658);
PAINT GREEN (-3462 4658);
FORCEPROP 2 LAST CDS_LIB mstr_standard
J 0
(-3400 4650);
DISPLAY 0.723404 (-3400 4650);
PAINT MONO (-3400 4650);
DISPLAY INVISIBLE (-3400 4650);
FORCEPROP 1 LAST BODY_TYPE PLUMBING
J 0
(-3400 4700);
DISPLAY 0.872340 (-3400 4700);
PAINT GREEN (-3400 4700);
DISPLAY INVISIBLE (-3400 4700);
FORCEPROP 1 LAST HDL_TAP TRUE
J 0
(-3075 4525);
DISPLAY 0.872340 (-3075 4525);
DISPLAY INVISIBLE (-3075 4525);
FORCEPROP 1 LAST PATH I186
J 0
(-3402 4650);
DISPLAY 0.872340 (-3402 4650);
PAINT GREEN (-3402 4650);
DISPLAY INVISIBLE (-3402 4650);
FORCEADD TAP..1
(-3400 4700);
FORCEPROP 3 LASTPIN (-3450 4700) SIG_NAME M_E_CPU0_SA_DQ<24>
J 0
(-3440 4710);
DISPLAY 0.659574 (-3440 4710);
PAINT MONO (-3440 4710);
DISPLAY INVISIBLE (-3440 4710);
FORCEPROP 1 LASTPIN (-3450 4700) BN 24
J 0
(-3462 4708);
DISPLAY 0.489362 (-3462 4708);
PAINT GREEN (-3462 4708);
FORCEPROP 2 LAST CDS_LIB mstr_standard
J 0
(-3400 4700);
DISPLAY 0.723404 (-3400 4700);
PAINT MONO (-3400 4700);
DISPLAY INVISIBLE (-3400 4700);
FORCEPROP 1 LAST BODY_TYPE PLUMBING
J 0
(-3400 4750);
DISPLAY 0.872340 (-3400 4750);
PAINT GREEN (-3400 4750);
DISPLAY INVISIBLE (-3400 4750);
FORCEPROP 1 LAST HDL_TAP TRUE
J 0
(-3075 4575);
DISPLAY 0.872340 (-3075 4575);
DISPLAY INVISIBLE (-3075 4575);
FORCEPROP 1 LAST PATH I187
J 0
(-3402 4700);
DISPLAY 0.872340 (-3402 4700);
PAINT GREEN (-3402 4700);
DISPLAY INVISIBLE (-3402 4700);
FORCEADD TAP..1
(-3400 4600);
FORCEPROP 3 LASTPIN (-3450 4600) SIG_NAME M_E_CPU0_SA_DQ<26>
J 0
(-3440 4610);
DISPLAY 0.659574 (-3440 4610);
PAINT MONO (-3440 4610);
DISPLAY INVISIBLE (-3440 4610);
FORCEPROP 1 LASTPIN (-3450 4600) BN 26
J 0
(-3462 4608);
DISPLAY 0.489362 (-3462 4608);
PAINT GREEN (-3462 4608);
FORCEPROP 2 LAST CDS_LIB mstr_standard
J 0
(-3400 4600);
DISPLAY 0.723404 (-3400 4600);
PAINT MONO (-3400 4600);
DISPLAY INVISIBLE (-3400 4600);
FORCEPROP 1 LAST BODY_TYPE PLUMBING
J 0
(-3400 4650);
DISPLAY 0.872340 (-3400 4650);
PAINT GREEN (-3400 4650);
DISPLAY INVISIBLE (-3400 4650);
FORCEPROP 1 LAST HDL_TAP TRUE
J 0
(-3075 4475);
DISPLAY 0.872340 (-3075 4475);
DISPLAY INVISIBLE (-3075 4475);
FORCEPROP 1 LAST PATH I188
J 0
(-3402 4600);
DISPLAY 0.872340 (-3402 4600);
PAINT GREEN (-3402 4600);
DISPLAY INVISIBLE (-3402 4600);
FORCEADD TAP..1
(-3400 4550);
FORCEPROP 3 LASTPIN (-3450 4550) SIG_NAME M_E_CPU0_SA_DQ<27>
J 0
(-3440 4560);
DISPLAY 0.659574 (-3440 4560);
PAINT MONO (-3440 4560);
DISPLAY INVISIBLE (-3440 4560);
FORCEPROP 1 LASTPIN (-3450 4550) BN 27
J 0
(-3462 4558);
DISPLAY 0.489362 (-3462 4558);
PAINT GREEN (-3462 4558);
FORCEPROP 2 LAST CDS_LIB mstr_standard
J 0
(-3400 4550);
DISPLAY 0.723404 (-3400 4550);
PAINT MONO (-3400 4550);
DISPLAY INVISIBLE (-3400 4550);
FORCEPROP 1 LAST BODY_TYPE PLUMBING
J 0
(-3400 4600);
DISPLAY 0.872340 (-3400 4600);
PAINT GREEN (-3400 4600);
DISPLAY INVISIBLE (-3400 4600);
FORCEPROP 1 LAST HDL_TAP TRUE
J 0
(-3075 4425);
DISPLAY 0.872340 (-3075 4425);
DISPLAY INVISIBLE (-3075 4425);
FORCEPROP 1 LAST PATH I189
J 0
(-3402 4550);
DISPLAY 0.872340 (-3402 4550);
PAINT GREEN (-3402 4550);
DISPLAY INVISIBLE (-3402 4550);
FORCEADD TAP..1
(-3400 4500);
FORCEPROP 3 LASTPIN (-3450 4500) SIG_NAME M_E_CPU0_SA_DQ<28>
J 0
(-3440 4510);
DISPLAY 0.659574 (-3440 4510);
PAINT MONO (-3440 4510);
DISPLAY INVISIBLE (-3440 4510);
FORCEPROP 1 LASTPIN (-3450 4500) BN 28
J 0
(-3462 4508);
DISPLAY 0.489362 (-3462 4508);
PAINT GREEN (-3462 4508);
FORCEPROP 2 LAST CDS_LIB mstr_standard
J 0
(-3400 4500);
DISPLAY 0.723404 (-3400 4500);
PAINT MONO (-3400 4500);
DISPLAY INVISIBLE (-3400 4500);
FORCEPROP 1 LAST BODY_TYPE PLUMBING
J 0
(-3400 4550);
DISPLAY 0.872340 (-3400 4550);
PAINT GREEN (-3400 4550);
DISPLAY INVISIBLE (-3400 4550);
FORCEPROP 1 LAST HDL_TAP TRUE
J 0
(-3075 4375);
DISPLAY 0.872340 (-3075 4375);
DISPLAY INVISIBLE (-3075 4375);
FORCEPROP 1 LAST PATH I190
J 0
(-3402 4500);
DISPLAY 0.872340 (-3402 4500);
PAINT GREEN (-3402 4500);
DISPLAY INVISIBLE (-3402 4500);
FORCEADD TAP..1
(-3400 4450);
FORCEPROP 3 LASTPIN (-3450 4450) SIG_NAME M_E_CPU0_SA_DQ<29>
J 0
(-3440 4460);
DISPLAY 0.659574 (-3440 4460);
PAINT MONO (-3440 4460);
DISPLAY INVISIBLE (-3440 4460);
FORCEPROP 1 LASTPIN (-3450 4450) BN 29
J 0
(-3462 4458);
DISPLAY 0.489362 (-3462 4458);
PAINT GREEN (-3462 4458);
FORCEPROP 2 LAST CDS_LIB mstr_standard
J 0
(-3400 4450);
DISPLAY 0.723404 (-3400 4450);
PAINT MONO (-3400 4450);
DISPLAY INVISIBLE (-3400 4450);
FORCEPROP 1 LAST BODY_TYPE PLUMBING
J 0
(-3400 4500);
DISPLAY 0.872340 (-3400 4500);
PAINT GREEN (-3400 4500);
DISPLAY INVISIBLE (-3400 4500);
FORCEPROP 1 LAST HDL_TAP TRUE
J 0
(-3075 4325);
DISPLAY 0.872340 (-3075 4325);
DISPLAY INVISIBLE (-3075 4325);
FORCEPROP 1 LAST PATH I191
J 0
(-3402 4450);
DISPLAY 0.872340 (-3402 4450);
PAINT GREEN (-3402 4450);
DISPLAY INVISIBLE (-3402 4450);
FORCEADD TAP..1
(-3400 4400);
FORCEPROP 3 LASTPIN (-3450 4400) SIG_NAME M_E_CPU0_SA_DQ<30>
J 0
(-3440 4410);
DISPLAY 0.659574 (-3440 4410);
PAINT MONO (-3440 4410);
DISPLAY INVISIBLE (-3440 4410);
FORCEPROP 1 LASTPIN (-3450 4400) BN 30
J 0
(-3462 4408);
DISPLAY 0.489362 (-3462 4408);
PAINT GREEN (-3462 4408);
FORCEPROP 2 LAST CDS_LIB mstr_standard
J 0
(-3400 4400);
DISPLAY 0.723404 (-3400 4400);
PAINT MONO (-3400 4400);
DISPLAY INVISIBLE (-3400 4400);
FORCEPROP 1 LAST BODY_TYPE PLUMBING
J 0
(-3400 4450);
DISPLAY 0.872340 (-3400 4450);
PAINT GREEN (-3400 4450);
DISPLAY INVISIBLE (-3400 4450);
FORCEPROP 1 LAST HDL_TAP TRUE
J 0
(-3075 4275);
DISPLAY 0.872340 (-3075 4275);
DISPLAY INVISIBLE (-3075 4275);
FORCEPROP 1 LAST PATH I192
J 0
(-3402 4400);
DISPLAY 0.872340 (-3402 4400);
PAINT GREEN (-3402 4400);
DISPLAY INVISIBLE (-3402 4400);
FORCEADD TAP..1
(-3400 4350);
FORCEPROP 3 LASTPIN (-3450 4350) SIG_NAME M_E_CPU0_SA_DQ<31>
J 0
(-3440 4360);
DISPLAY 0.659574 (-3440 4360);
PAINT MONO (-3440 4360);
DISPLAY INVISIBLE (-3440 4360);
FORCEPROP 1 LASTPIN (-3450 4350) BN 31
J 0
(-3462 4358);
DISPLAY 0.489362 (-3462 4358);
PAINT GREEN (-3462 4358);
FORCEPROP 2 LAST CDS_LIB mstr_standard
J 0
(-3400 4350);
DISPLAY 0.723404 (-3400 4350);
PAINT MONO (-3400 4350);
DISPLAY INVISIBLE (-3400 4350);
FORCEPROP 1 LAST BODY_TYPE PLUMBING
J 0
(-3400 4400);
DISPLAY 0.872340 (-3400 4400);
PAINT GREEN (-3400 4400);
DISPLAY INVISIBLE (-3400 4400);
FORCEPROP 1 LAST HDL_TAP TRUE
J 0
(-3075 4225);
DISPLAY 0.872340 (-3075 4225);
DISPLAY INVISIBLE (-3075 4225);
FORCEPROP 1 LAST PATH I193
J 0
(-3402 4350);
DISPLAY 0.872340 (-3402 4350);
PAINT GREEN (-3402 4350);
DISPLAY INVISIBLE (-3402 4350);
FORCEADD TAP..1
(-3400 4250);
FORCEPROP 3 LASTPIN (-3450 4250) SIG_NAME M_E_CPU0_SB_DQ<0>
J 0
(-3440 4260);
DISPLAY 0.659574 (-3440 4260);
PAINT MONO (-3440 4260);
DISPLAY INVISIBLE (-3440 4260);
FORCEPROP 1 LASTPIN (-3450 4250) BN 0
J 0
(-3462 4258);
DISPLAY 0.489362 (-3462 4258);
PAINT GREEN (-3462 4258);
FORCEPROP 2 LAST CDS_LIB mstr_standard
J 0
(-3400 4250);
DISPLAY 0.723404 (-3400 4250);
PAINT MONO (-3400 4250);
DISPLAY INVISIBLE (-3400 4250);
FORCEPROP 1 LAST BODY_TYPE PLUMBING
J 0
(-3400 4300);
DISPLAY 0.872340 (-3400 4300);
PAINT GREEN (-3400 4300);
DISPLAY INVISIBLE (-3400 4300);
FORCEPROP 1 LAST HDL_TAP TRUE
J 0
(-3075 4125);
DISPLAY 0.872340 (-3075 4125);
DISPLAY INVISIBLE (-3075 4125);
FORCEPROP 1 LAST PATH I194
J 0
(-3402 4250);
DISPLAY 0.872340 (-3402 4250);
PAINT GREEN (-3402 4250);
DISPLAY INVISIBLE (-3402 4250);
FORCEADD TAP..1
(-3400 4100);
FORCEPROP 3 LASTPIN (-3450 4100) SIG_NAME M_E_CPU0_SB_DQ<3>
J 0
(-3440 4110);
DISPLAY 0.659574 (-3440 4110);
PAINT MONO (-3440 4110);
DISPLAY INVISIBLE (-3440 4110);
FORCEPROP 1 LASTPIN (-3450 4100) BN 3
J 0
(-3462 4108);
DISPLAY 0.489362 (-3462 4108);
PAINT GREEN (-3462 4108);
FORCEPROP 2 LAST CDS_LIB mstr_standard
J 0
(-3400 4100);
DISPLAY 0.723404 (-3400 4100);
PAINT MONO (-3400 4100);
DISPLAY INVISIBLE (-3400 4100);
FORCEPROP 1 LAST BODY_TYPE PLUMBING
J 0
(-3400 4150);
DISPLAY 0.872340 (-3400 4150);
PAINT GREEN (-3400 4150);
DISPLAY INVISIBLE (-3400 4150);
FORCEPROP 1 LAST HDL_TAP TRUE
J 0
(-3075 3975);
DISPLAY 0.872340 (-3075 3975);
DISPLAY INVISIBLE (-3075 3975);
FORCEPROP 1 LAST PATH I195
J 0
(-3402 4100);
DISPLAY 0.872340 (-3402 4100);
PAINT GREEN (-3402 4100);
DISPLAY INVISIBLE (-3402 4100);
FORCEADD TAP..1
(-3400 4200);
FORCEPROP 3 LASTPIN (-3450 4200) SIG_NAME M_E_CPU0_SB_DQ<1>
J 0
(-3440 4210);
DISPLAY 0.659574 (-3440 4210);
PAINT MONO (-3440 4210);
DISPLAY INVISIBLE (-3440 4210);
FORCEPROP 1 LASTPIN (-3450 4200) BN 1
J 0
(-3462 4208);
DISPLAY 0.489362 (-3462 4208);
PAINT GREEN (-3462 4208);
FORCEPROP 2 LAST CDS_LIB mstr_standard
J 0
(-3400 4200);
DISPLAY 0.723404 (-3400 4200);
PAINT MONO (-3400 4200);
DISPLAY INVISIBLE (-3400 4200);
FORCEPROP 1 LAST BODY_TYPE PLUMBING
J 0
(-3400 4250);
DISPLAY 0.872340 (-3400 4250);
PAINT GREEN (-3400 4250);
DISPLAY INVISIBLE (-3400 4250);
FORCEPROP 1 LAST HDL_TAP TRUE
J 0
(-3075 4075);
DISPLAY 0.872340 (-3075 4075);
DISPLAY INVISIBLE (-3075 4075);
FORCEPROP 1 LAST PATH I196
J 0
(-3402 4200);
DISPLAY 0.872340 (-3402 4200);
PAINT GREEN (-3402 4200);
DISPLAY INVISIBLE (-3402 4200);
FORCEADD TAP..1
(-3400 4150);
FORCEPROP 3 LASTPIN (-3450 4150) SIG_NAME M_E_CPU0_SB_DQ<2>
J 0
(-3440 4160);
DISPLAY 0.659574 (-3440 4160);
PAINT MONO (-3440 4160);
DISPLAY INVISIBLE (-3440 4160);
FORCEPROP 1 LASTPIN (-3450 4150) BN 2
J 0
(-3462 4158);
DISPLAY 0.489362 (-3462 4158);
PAINT GREEN (-3462 4158);
FORCEPROP 2 LAST CDS_LIB mstr_standard
J 0
(-3400 4150);
DISPLAY 0.723404 (-3400 4150);
PAINT MONO (-3400 4150);
DISPLAY INVISIBLE (-3400 4150);
FORCEPROP 1 LAST BODY_TYPE PLUMBING
J 0
(-3400 4200);
DISPLAY 0.872340 (-3400 4200);
PAINT GREEN (-3400 4200);
DISPLAY INVISIBLE (-3400 4200);
FORCEPROP 1 LAST HDL_TAP TRUE
J 0
(-3075 4025);
DISPLAY 0.872340 (-3075 4025);
DISPLAY INVISIBLE (-3075 4025);
FORCEPROP 1 LAST PATH I197
J 0
(-3402 4150);
DISPLAY 0.872340 (-3402 4150);
PAINT GREEN (-3402 4150);
DISPLAY INVISIBLE (-3402 4150);
FORCEADD OFFPAGE..6
R 2
(-2800 2500);
FORCEPROP 2 LAST $XR0 90 
J 0
(-2586 2500);
DISPLAY 0.638298 (-2586 2500);
PAINT MONO (-2586 2500);
FORCEPROP 2 LAST CDS_LIB mstr_standard
J 2
(-2800 2500);
DISPLAY 0.723404 (-2800 2500);
PAINT MONO (-2800 2500);
DISPLAY INVISIBLE (-2800 2500);
FORCEPROP 1 LAST OFFPAGE TRUE
J 2
(-3125 2375);
DISPLAY 0.872340 (-3125 2375);
PAINT GREEN (-3125 2375);
DISPLAY INVISIBLE (-3125 2375);
FORCEPROP 1 LAST COMMENT_BODY TRUE
J 2
(-2900 2425);
DISPLAY 0.872340 (-2900 2425);
PAINT GREEN (-2900 2425);
DISPLAY INVISIBLE (-2900 2425);
FORCEPROP 2 LAST PATH I198
J 0
(-2575 2550);
DISPLAY 1.021277 (-2575 2550);
DISPLAY INVISIBLE (-2575 2550);
FORCEADD TAP..1
(-3400 4000);
FORCEPROP 3 LASTPIN (-3450 4000) SIG_NAME M_E_CPU0_SB_DQ<5>
J 0
(-3440 4010);
DISPLAY 0.659574 (-3440 4010);
PAINT MONO (-3440 4010);
DISPLAY INVISIBLE (-3440 4010);
FORCEPROP 1 LASTPIN (-3450 4000) BN 5
J 0
(-3462 4008);
DISPLAY 0.489362 (-3462 4008);
PAINT GREEN (-3462 4008);
FORCEPROP 2 LAST CDS_LIB mstr_standard
J 0
(-3400 4000);
DISPLAY 0.723404 (-3400 4000);
PAINT MONO (-3400 4000);
DISPLAY INVISIBLE (-3400 4000);
FORCEPROP 1 LAST BODY_TYPE PLUMBING
J 0
(-3400 4050);
DISPLAY 0.872340 (-3400 4050);
PAINT GREEN (-3400 4050);
DISPLAY INVISIBLE (-3400 4050);
FORCEPROP 1 LAST HDL_TAP TRUE
J 0
(-3075 3875);
DISPLAY 0.872340 (-3075 3875);
DISPLAY INVISIBLE (-3075 3875);
FORCEPROP 1 LAST PATH I199
J 0
(-3402 4000);
DISPLAY 0.872340 (-3402 4000);
PAINT GREEN (-3402 4000);
DISPLAY INVISIBLE (-3402 4000);
FORCEADD TAP..1
(-3400 4050);
FORCEPROP 3 LASTPIN (-3450 4050) SIG_NAME M_E_CPU0_SB_DQ<4>
J 0
(-3440 4060);
DISPLAY 0.659574 (-3440 4060);
PAINT MONO (-3440 4060);
DISPLAY INVISIBLE (-3440 4060);
FORCEPROP 1 LASTPIN (-3450 4050) BN 4
J 0
(-3462 4058);
DISPLAY 0.489362 (-3462 4058);
PAINT GREEN (-3462 4058);
FORCEPROP 2 LAST CDS_LIB mstr_standard
J 0
(-3400 4050);
DISPLAY 0.723404 (-3400 4050);
PAINT MONO (-3400 4050);
DISPLAY INVISIBLE (-3400 4050);
FORCEPROP 1 LAST BODY_TYPE PLUMBING
J 0
(-3400 4100);
DISPLAY 0.872340 (-3400 4100);
PAINT GREEN (-3400 4100);
DISPLAY INVISIBLE (-3400 4100);
FORCEPROP 1 LAST HDL_TAP TRUE
J 0
(-3075 3925);
DISPLAY 0.872340 (-3075 3925);
DISPLAY INVISIBLE (-3075 3925);
FORCEPROP 1 LAST PATH I200
J 0
(-3402 4050);
DISPLAY 0.872340 (-3402 4050);
PAINT GREEN (-3402 4050);
DISPLAY INVISIBLE (-3402 4050);
FORCEADD TAP..1
(-3400 3950);
FORCEPROP 3 LASTPIN (-3450 3950) SIG_NAME M_E_CPU0_SB_DQ<6>
J 0
(-3440 3960);
DISPLAY 0.659574 (-3440 3960);
PAINT MONO (-3440 3960);
DISPLAY INVISIBLE (-3440 3960);
FORCEPROP 1 LASTPIN (-3450 3950) BN 6
J 0
(-3462 3958);
DISPLAY 0.489362 (-3462 3958);
PAINT GREEN (-3462 3958);
FORCEPROP 2 LAST CDS_LIB mstr_standard
J 0
(-3400 3950);
DISPLAY 0.723404 (-3400 3950);
PAINT MONO (-3400 3950);
DISPLAY INVISIBLE (-3400 3950);
FORCEPROP 1 LAST BODY_TYPE PLUMBING
J 0
(-3400 4000);
DISPLAY 0.872340 (-3400 4000);
PAINT GREEN (-3400 4000);
DISPLAY INVISIBLE (-3400 4000);
FORCEPROP 1 LAST HDL_TAP TRUE
J 0
(-3075 3825);
DISPLAY 0.872340 (-3075 3825);
DISPLAY INVISIBLE (-3075 3825);
FORCEPROP 1 LAST PATH I201
J 0
(-3402 3950);
DISPLAY 0.872340 (-3402 3950);
PAINT GREEN (-3402 3950);
DISPLAY INVISIBLE (-3402 3950);
FORCEADD TAP..1
(-3400 3900);
FORCEPROP 3 LASTPIN (-3450 3900) SIG_NAME M_E_CPU0_SB_DQ<7>
J 0
(-3440 3910);
DISPLAY 0.659574 (-3440 3910);
PAINT MONO (-3440 3910);
DISPLAY INVISIBLE (-3440 3910);
FORCEPROP 1 LASTPIN (-3450 3900) BN 7
J 0
(-3462 3908);
DISPLAY 0.489362 (-3462 3908);
PAINT GREEN (-3462 3908);
FORCEPROP 2 LAST CDS_LIB mstr_standard
J 0
(-3400 3900);
DISPLAY 0.723404 (-3400 3900);
PAINT MONO (-3400 3900);
DISPLAY INVISIBLE (-3400 3900);
FORCEPROP 1 LAST BODY_TYPE PLUMBING
J 0
(-3400 3950);
DISPLAY 0.872340 (-3400 3950);
PAINT GREEN (-3400 3950);
DISPLAY INVISIBLE (-3400 3950);
FORCEPROP 1 LAST HDL_TAP TRUE
J 0
(-3075 3775);
DISPLAY 0.872340 (-3075 3775);
DISPLAY INVISIBLE (-3075 3775);
FORCEPROP 1 LAST PATH I202
J 0
(-3402 3900);
DISPLAY 0.872340 (-3402 3900);
PAINT GREEN (-3402 3900);
DISPLAY INVISIBLE (-3402 3900);
FORCEADD TAP..1
(-3400 3800);
FORCEPROP 3 LASTPIN (-3450 3800) SIG_NAME M_E_CPU0_SB_DQ<8>
J 0
(-3440 3810);
DISPLAY 0.659574 (-3440 3810);
PAINT MONO (-3440 3810);
DISPLAY INVISIBLE (-3440 3810);
FORCEPROP 1 LASTPIN (-3450 3800) BN 8
J 0
(-3462 3808);
DISPLAY 0.489362 (-3462 3808);
PAINT GREEN (-3462 3808);
FORCEPROP 2 LAST CDS_LIB mstr_standard
J 0
(-3400 3800);
DISPLAY 0.723404 (-3400 3800);
PAINT MONO (-3400 3800);
DISPLAY INVISIBLE (-3400 3800);
FORCEPROP 1 LAST BODY_TYPE PLUMBING
J 0
(-3400 3850);
DISPLAY 0.872340 (-3400 3850);
PAINT GREEN (-3400 3850);
DISPLAY INVISIBLE (-3400 3850);
FORCEPROP 1 LAST HDL_TAP TRUE
J 0
(-3075 3675);
DISPLAY 0.872340 (-3075 3675);
DISPLAY INVISIBLE (-3075 3675);
FORCEPROP 1 LAST PATH I203
J 0
(-3402 3800);
DISPLAY 0.872340 (-3402 3800);
PAINT GREEN (-3402 3800);
DISPLAY INVISIBLE (-3402 3800);
FORCEADD TAP..1
(-3400 3750);
FORCEPROP 3 LASTPIN (-3450 3750) SIG_NAME M_E_CPU0_SB_DQ<9>
J 0
(-3440 3760);
DISPLAY 0.659574 (-3440 3760);
PAINT MONO (-3440 3760);
DISPLAY INVISIBLE (-3440 3760);
FORCEPROP 1 LASTPIN (-3450 3750) BN 9
J 0
(-3462 3758);
DISPLAY 0.489362 (-3462 3758);
PAINT GREEN (-3462 3758);
FORCEPROP 2 LAST CDS_LIB mstr_standard
J 0
(-3400 3750);
DISPLAY 0.723404 (-3400 3750);
PAINT MONO (-3400 3750);
DISPLAY INVISIBLE (-3400 3750);
FORCEPROP 1 LAST BODY_TYPE PLUMBING
J 0
(-3400 3800);
DISPLAY 0.872340 (-3400 3800);
PAINT GREEN (-3400 3800);
DISPLAY INVISIBLE (-3400 3800);
FORCEPROP 1 LAST HDL_TAP TRUE
J 0
(-3075 3625);
DISPLAY 0.872340 (-3075 3625);
DISPLAY INVISIBLE (-3075 3625);
FORCEPROP 1 LAST PATH I204
J 0
(-3402 3750);
DISPLAY 0.872340 (-3402 3750);
PAINT GREEN (-3402 3750);
DISPLAY INVISIBLE (-3402 3750);
FORCEADD TAP..1
(-3400 3600);
FORCEPROP 3 LASTPIN (-3450 3600) SIG_NAME M_E_CPU0_SB_DQ<12>
J 0
(-3440 3610);
DISPLAY 0.659574 (-3440 3610);
PAINT MONO (-3440 3610);
DISPLAY INVISIBLE (-3440 3610);
FORCEPROP 1 LASTPIN (-3450 3600) BN 12
J 0
(-3462 3608);
DISPLAY 0.489362 (-3462 3608);
PAINT GREEN (-3462 3608);
FORCEPROP 2 LAST CDS_LIB mstr_standard
J 0
(-3400 3600);
DISPLAY 0.723404 (-3400 3600);
PAINT MONO (-3400 3600);
DISPLAY INVISIBLE (-3400 3600);
FORCEPROP 1 LAST BODY_TYPE PLUMBING
J 0
(-3400 3650);
DISPLAY 0.872340 (-3400 3650);
PAINT GREEN (-3400 3650);
DISPLAY INVISIBLE (-3400 3650);
FORCEPROP 1 LAST HDL_TAP TRUE
J 0
(-3075 3475);
DISPLAY 0.872340 (-3075 3475);
DISPLAY INVISIBLE (-3075 3475);
FORCEPROP 1 LAST PATH I205
J 0
(-3402 3600);
DISPLAY 0.872340 (-3402 3600);
PAINT GREEN (-3402 3600);
DISPLAY INVISIBLE (-3402 3600);
FORCEADD TAP..1
(-3400 3650);
FORCEPROP 3 LASTPIN (-3450 3650) SIG_NAME M_E_CPU0_SB_DQ<11>
J 0
(-3440 3660);
DISPLAY 0.659574 (-3440 3660);
PAINT MONO (-3440 3660);
DISPLAY INVISIBLE (-3440 3660);
FORCEPROP 1 LASTPIN (-3450 3650) BN 11
J 0
(-3462 3658);
DISPLAY 0.489362 (-3462 3658);
PAINT GREEN (-3462 3658);
FORCEPROP 2 LAST CDS_LIB mstr_standard
J 0
(-3400 3650);
DISPLAY 0.723404 (-3400 3650);
PAINT MONO (-3400 3650);
DISPLAY INVISIBLE (-3400 3650);
FORCEPROP 1 LAST BODY_TYPE PLUMBING
J 0
(-3400 3700);
DISPLAY 0.872340 (-3400 3700);
PAINT GREEN (-3400 3700);
DISPLAY INVISIBLE (-3400 3700);
FORCEPROP 1 LAST HDL_TAP TRUE
J 0
(-3075 3525);
DISPLAY 0.872340 (-3075 3525);
DISPLAY INVISIBLE (-3075 3525);
FORCEPROP 1 LAST PATH I206
J 0
(-3402 3650);
DISPLAY 0.872340 (-3402 3650);
PAINT GREEN (-3402 3650);
DISPLAY INVISIBLE (-3402 3650);
FORCEADD TAP..1
(-3400 3700);
FORCEPROP 3 LASTPIN (-3450 3700) SIG_NAME M_E_CPU0_SB_DQ<10>
J 0
(-3440 3710);
DISPLAY 0.659574 (-3440 3710);
PAINT MONO (-3440 3710);
DISPLAY INVISIBLE (-3440 3710);
FORCEPROP 1 LASTPIN (-3450 3700) BN 10
J 0
(-3462 3708);
DISPLAY 0.489362 (-3462 3708);
PAINT GREEN (-3462 3708);
FORCEPROP 2 LAST CDS_LIB mstr_standard
J 0
(-3400 3700);
DISPLAY 0.723404 (-3400 3700);
PAINT MONO (-3400 3700);
DISPLAY INVISIBLE (-3400 3700);
FORCEPROP 1 LAST BODY_TYPE PLUMBING
J 0
(-3400 3750);
DISPLAY 0.872340 (-3400 3750);
PAINT GREEN (-3400 3750);
DISPLAY INVISIBLE (-3400 3750);
FORCEPROP 1 LAST HDL_TAP TRUE
J 0
(-3075 3575);
DISPLAY 0.872340 (-3075 3575);
DISPLAY INVISIBLE (-3075 3575);
FORCEPROP 1 LAST PATH I207
J 0
(-3402 3700);
DISPLAY 0.872340 (-3402 3700);
PAINT GREEN (-3402 3700);
DISPLAY INVISIBLE (-3402 3700);
FORCEADD TAP..1
(-3400 3500);
FORCEPROP 3 LASTPIN (-3450 3500) SIG_NAME M_E_CPU0_SB_DQ<14>
J 0
(-3440 3510);
DISPLAY 0.659574 (-3440 3510);
PAINT MONO (-3440 3510);
DISPLAY INVISIBLE (-3440 3510);
FORCEPROP 1 LASTPIN (-3450 3500) BN 14
J 0
(-3462 3508);
DISPLAY 0.489362 (-3462 3508);
PAINT GREEN (-3462 3508);
FORCEPROP 2 LAST CDS_LIB mstr_standard
J 0
(-3400 3500);
DISPLAY 0.723404 (-3400 3500);
PAINT MONO (-3400 3500);
DISPLAY INVISIBLE (-3400 3500);
FORCEPROP 1 LAST BODY_TYPE PLUMBING
J 0
(-3400 3550);
DISPLAY 0.872340 (-3400 3550);
PAINT GREEN (-3400 3550);
DISPLAY INVISIBLE (-3400 3550);
FORCEPROP 1 LAST HDL_TAP TRUE
J 0
(-3075 3375);
DISPLAY 0.872340 (-3075 3375);
DISPLAY INVISIBLE (-3075 3375);
FORCEPROP 1 LAST PATH I208
J 0
(-3402 3500);
DISPLAY 0.872340 (-3402 3500);
PAINT GREEN (-3402 3500);
DISPLAY INVISIBLE (-3402 3500);
FORCEADD TAP..1
(-3400 3550);
FORCEPROP 3 LASTPIN (-3450 3550) SIG_NAME M_E_CPU0_SB_DQ<13>
J 0
(-3440 3560);
DISPLAY 0.659574 (-3440 3560);
PAINT MONO (-3440 3560);
DISPLAY INVISIBLE (-3440 3560);
FORCEPROP 1 LASTPIN (-3450 3550) BN 13
J 0
(-3462 3558);
DISPLAY 0.489362 (-3462 3558);
PAINT GREEN (-3462 3558);
FORCEPROP 2 LAST CDS_LIB mstr_standard
J 0
(-3400 3550);
DISPLAY 0.723404 (-3400 3550);
PAINT MONO (-3400 3550);
DISPLAY INVISIBLE (-3400 3550);
FORCEPROP 1 LAST BODY_TYPE PLUMBING
J 0
(-3400 3600);
DISPLAY 0.872340 (-3400 3600);
PAINT GREEN (-3400 3600);
DISPLAY INVISIBLE (-3400 3600);
FORCEPROP 1 LAST HDL_TAP TRUE
J 0
(-3075 3425);
DISPLAY 0.872340 (-3075 3425);
DISPLAY INVISIBLE (-3075 3425);
FORCEPROP 1 LAST PATH I209
J 0
(-3402 3550);
DISPLAY 0.872340 (-3402 3550);
PAINT GREEN (-3402 3550);
DISPLAY INVISIBLE (-3402 3550);
FORCEADD TAP..1
(-3400 3450);
FORCEPROP 3 LASTPIN (-3450 3450) SIG_NAME M_E_CPU0_SB_DQ<15>
J 0
(-3440 3460);
DISPLAY 0.659574 (-3440 3460);
PAINT MONO (-3440 3460);
DISPLAY INVISIBLE (-3440 3460);
FORCEPROP 1 LASTPIN (-3450 3450) BN 15
J 0
(-3462 3458);
DISPLAY 0.489362 (-3462 3458);
PAINT GREEN (-3462 3458);
FORCEPROP 2 LAST CDS_LIB mstr_standard
J 0
(-3400 3450);
DISPLAY 0.723404 (-3400 3450);
PAINT MONO (-3400 3450);
DISPLAY INVISIBLE (-3400 3450);
FORCEPROP 1 LAST BODY_TYPE PLUMBING
J 0
(-3400 3500);
DISPLAY 0.872340 (-3400 3500);
PAINT GREEN (-3400 3500);
DISPLAY INVISIBLE (-3400 3500);
FORCEPROP 1 LAST HDL_TAP TRUE
J 0
(-3075 3325);
DISPLAY 0.872340 (-3075 3325);
DISPLAY INVISIBLE (-3075 3325);
FORCEPROP 1 LAST PATH I210
J 0
(-3402 3450);
DISPLAY 0.872340 (-3402 3450);
PAINT GREEN (-3402 3450);
DISPLAY INVISIBLE (-3402 3450);
FORCEADD TAP..1
(-3400 3350);
FORCEPROP 3 LASTPIN (-3450 3350) SIG_NAME M_E_CPU0_SB_DQ<16>
J 0
(-3440 3360);
DISPLAY 0.659574 (-3440 3360);
PAINT MONO (-3440 3360);
DISPLAY INVISIBLE (-3440 3360);
FORCEPROP 1 LASTPIN (-3450 3350) BN 16
J 0
(-3462 3358);
DISPLAY 0.489362 (-3462 3358);
PAINT GREEN (-3462 3358);
FORCEPROP 2 LAST CDS_LIB mstr_standard
J 0
(-3400 3350);
DISPLAY 0.723404 (-3400 3350);
PAINT MONO (-3400 3350);
DISPLAY INVISIBLE (-3400 3350);
FORCEPROP 1 LAST BODY_TYPE PLUMBING
J 0
(-3400 3400);
DISPLAY 0.872340 (-3400 3400);
PAINT GREEN (-3400 3400);
DISPLAY INVISIBLE (-3400 3400);
FORCEPROP 1 LAST HDL_TAP TRUE
J 0
(-3075 3225);
DISPLAY 0.872340 (-3075 3225);
DISPLAY INVISIBLE (-3075 3225);
FORCEPROP 1 LAST PATH I211
J 0
(-3402 3350);
DISPLAY 0.872340 (-3402 3350);
PAINT GREEN (-3402 3350);
DISPLAY INVISIBLE (-3402 3350);
FORCEADD TAP..1
(-3400 3300);
FORCEPROP 3 LASTPIN (-3450 3300) SIG_NAME M_E_CPU0_SB_DQ<17>
J 0
(-3440 3310);
DISPLAY 0.659574 (-3440 3310);
PAINT MONO (-3440 3310);
DISPLAY INVISIBLE (-3440 3310);
FORCEPROP 1 LASTPIN (-3450 3300) BN 17
J 0
(-3462 3308);
DISPLAY 0.489362 (-3462 3308);
PAINT GREEN (-3462 3308);
FORCEPROP 2 LAST CDS_LIB mstr_standard
J 0
(-3400 3300);
DISPLAY 0.723404 (-3400 3300);
PAINT MONO (-3400 3300);
DISPLAY INVISIBLE (-3400 3300);
FORCEPROP 1 LAST BODY_TYPE PLUMBING
J 0
(-3400 3350);
DISPLAY 0.872340 (-3400 3350);
PAINT GREEN (-3400 3350);
DISPLAY INVISIBLE (-3400 3350);
FORCEPROP 1 LAST HDL_TAP TRUE
J 0
(-3075 3175);
DISPLAY 0.872340 (-3075 3175);
DISPLAY INVISIBLE (-3075 3175);
FORCEPROP 1 LAST PATH I212
J 0
(-3402 3300);
DISPLAY 0.872340 (-3402 3300);
PAINT GREEN (-3402 3300);
DISPLAY INVISIBLE (-3402 3300);
FORCEADD TAP..1
(-3400 3250);
FORCEPROP 3 LASTPIN (-3450 3250) SIG_NAME M_E_CPU0_SB_DQ<18>
J 0
(-3440 3260);
DISPLAY 0.659574 (-3440 3260);
PAINT MONO (-3440 3260);
DISPLAY INVISIBLE (-3440 3260);
FORCEPROP 1 LASTPIN (-3450 3250) BN 18
J 0
(-3462 3258);
DISPLAY 0.489362 (-3462 3258);
PAINT GREEN (-3462 3258);
FORCEPROP 2 LAST CDS_LIB mstr_standard
J 0
(-3400 3250);
DISPLAY 0.723404 (-3400 3250);
PAINT MONO (-3400 3250);
DISPLAY INVISIBLE (-3400 3250);
FORCEPROP 1 LAST BODY_TYPE PLUMBING
J 0
(-3400 3300);
DISPLAY 0.872340 (-3400 3300);
PAINT GREEN (-3400 3300);
DISPLAY INVISIBLE (-3400 3300);
FORCEPROP 1 LAST HDL_TAP TRUE
J 0
(-3075 3125);
DISPLAY 0.872340 (-3075 3125);
DISPLAY INVISIBLE (-3075 3125);
FORCEPROP 1 LAST PATH I213
J 0
(-3402 3250);
DISPLAY 0.872340 (-3402 3250);
PAINT GREEN (-3402 3250);
DISPLAY INVISIBLE (-3402 3250);
FORCEADD TAP..1
(-3400 3200);
FORCEPROP 3 LASTPIN (-3450 3200) SIG_NAME M_E_CPU0_SB_DQ<19>
J 0
(-3440 3210);
DISPLAY 0.659574 (-3440 3210);
PAINT MONO (-3440 3210);
DISPLAY INVISIBLE (-3440 3210);
FORCEPROP 1 LASTPIN (-3450 3200) BN 19
J 0
(-3462 3208);
DISPLAY 0.489362 (-3462 3208);
PAINT GREEN (-3462 3208);
FORCEPROP 2 LAST CDS_LIB mstr_standard
J 0
(-3400 3200);
DISPLAY 0.723404 (-3400 3200);
PAINT MONO (-3400 3200);
DISPLAY INVISIBLE (-3400 3200);
FORCEPROP 1 LAST BODY_TYPE PLUMBING
J 0
(-3400 3250);
DISPLAY 0.872340 (-3400 3250);
PAINT GREEN (-3400 3250);
DISPLAY INVISIBLE (-3400 3250);
FORCEPROP 1 LAST HDL_TAP TRUE
J 0
(-3075 3075);
DISPLAY 0.872340 (-3075 3075);
DISPLAY INVISIBLE (-3075 3075);
FORCEPROP 1 LAST PATH I214
J 0
(-3402 3200);
DISPLAY 0.872340 (-3402 3200);
PAINT GREEN (-3402 3200);
DISPLAY INVISIBLE (-3402 3200);
FORCEADD TAP..1
(-3400 3150);
FORCEPROP 3 LASTPIN (-3450 3150) SIG_NAME M_E_CPU0_SB_DQ<20>
J 0
(-3440 3160);
DISPLAY 0.659574 (-3440 3160);
PAINT MONO (-3440 3160);
DISPLAY INVISIBLE (-3440 3160);
FORCEPROP 1 LASTPIN (-3450 3150) BN 20
J 0
(-3462 3158);
DISPLAY 0.489362 (-3462 3158);
PAINT GREEN (-3462 3158);
FORCEPROP 2 LAST CDS_LIB mstr_standard
J 0
(-3400 3150);
DISPLAY 0.723404 (-3400 3150);
PAINT MONO (-3400 3150);
DISPLAY INVISIBLE (-3400 3150);
FORCEPROP 1 LAST BODY_TYPE PLUMBING
J 0
(-3400 3200);
DISPLAY 0.872340 (-3400 3200);
PAINT GREEN (-3400 3200);
DISPLAY INVISIBLE (-3400 3200);
FORCEPROP 1 LAST HDL_TAP TRUE
J 0
(-3075 3025);
DISPLAY 0.872340 (-3075 3025);
DISPLAY INVISIBLE (-3075 3025);
FORCEPROP 1 LAST PATH I215
J 0
(-3402 3150);
DISPLAY 0.872340 (-3402 3150);
PAINT GREEN (-3402 3150);
DISPLAY INVISIBLE (-3402 3150);
FORCEADD TAP..1
(-3400 3100);
FORCEPROP 3 LASTPIN (-3450 3100) SIG_NAME M_E_CPU0_SB_DQ<21>
J 0
(-3440 3110);
DISPLAY 0.659574 (-3440 3110);
PAINT MONO (-3440 3110);
DISPLAY INVISIBLE (-3440 3110);
FORCEPROP 1 LASTPIN (-3450 3100) BN 21
J 0
(-3462 3108);
DISPLAY 0.489362 (-3462 3108);
PAINT GREEN (-3462 3108);
FORCEPROP 2 LAST CDS_LIB mstr_standard
J 0
(-3400 3100);
DISPLAY 0.723404 (-3400 3100);
PAINT MONO (-3400 3100);
DISPLAY INVISIBLE (-3400 3100);
FORCEPROP 1 LAST BODY_TYPE PLUMBING
J 0
(-3400 3150);
DISPLAY 0.872340 (-3400 3150);
PAINT GREEN (-3400 3150);
DISPLAY INVISIBLE (-3400 3150);
FORCEPROP 1 LAST HDL_TAP TRUE
J 0
(-3075 2975);
DISPLAY 0.872340 (-3075 2975);
DISPLAY INVISIBLE (-3075 2975);
FORCEPROP 1 LAST PATH I216
J 0
(-3402 3100);
DISPLAY 0.872340 (-3402 3100);
PAINT GREEN (-3402 3100);
DISPLAY INVISIBLE (-3402 3100);
FORCEADD TAP..1
(-3400 3000);
FORCEPROP 3 LASTPIN (-3450 3000) SIG_NAME M_E_CPU0_SB_DQ<23>
J 0
(-3440 3010);
DISPLAY 0.659574 (-3440 3010);
PAINT MONO (-3440 3010);
DISPLAY INVISIBLE (-3440 3010);
FORCEPROP 1 LASTPIN (-3450 3000) BN 23
J 0
(-3462 3008);
DISPLAY 0.489362 (-3462 3008);
PAINT GREEN (-3462 3008);
FORCEPROP 2 LAST CDS_LIB mstr_standard
J 0
(-3400 3000);
DISPLAY 0.723404 (-3400 3000);
PAINT MONO (-3400 3000);
DISPLAY INVISIBLE (-3400 3000);
FORCEPROP 1 LAST BODY_TYPE PLUMBING
J 0
(-3400 3050);
DISPLAY 0.872340 (-3400 3050);
PAINT GREEN (-3400 3050);
DISPLAY INVISIBLE (-3400 3050);
FORCEPROP 1 LAST HDL_TAP TRUE
J 0
(-3075 2875);
DISPLAY 0.872340 (-3075 2875);
DISPLAY INVISIBLE (-3075 2875);
FORCEPROP 1 LAST PATH I217
J 0
(-3402 3000);
DISPLAY 0.872340 (-3402 3000);
PAINT GREEN (-3402 3000);
DISPLAY INVISIBLE (-3402 3000);
FORCEADD TAP..1
(-3400 3050);
FORCEPROP 3 LASTPIN (-3450 3050) SIG_NAME M_E_CPU0_SB_DQ<22>
J 0
(-3440 3060);
DISPLAY 0.659574 (-3440 3060);
PAINT MONO (-3440 3060);
DISPLAY INVISIBLE (-3440 3060);
FORCEPROP 1 LASTPIN (-3450 3050) BN 22
J 0
(-3462 3058);
DISPLAY 0.489362 (-3462 3058);
PAINT GREEN (-3462 3058);
FORCEPROP 2 LAST CDS_LIB mstr_standard
J 0
(-3400 3050);
DISPLAY 0.723404 (-3400 3050);
PAINT MONO (-3400 3050);
DISPLAY INVISIBLE (-3400 3050);
FORCEPROP 1 LAST BODY_TYPE PLUMBING
J 0
(-3400 3100);
DISPLAY 0.872340 (-3400 3100);
PAINT GREEN (-3400 3100);
DISPLAY INVISIBLE (-3400 3100);
FORCEPROP 1 LAST HDL_TAP TRUE
J 0
(-3075 2925);
DISPLAY 0.872340 (-3075 2925);
DISPLAY INVISIBLE (-3075 2925);
FORCEPROP 1 LAST PATH I218
J 0
(-3402 3050);
DISPLAY 0.872340 (-3402 3050);
PAINT GREEN (-3402 3050);
DISPLAY INVISIBLE (-3402 3050);
FORCEADD TAP..1
(-3400 2900);
FORCEPROP 3 LASTPIN (-3450 2900) SIG_NAME M_E_CPU0_SB_DQ<24>
J 0
(-3440 2910);
DISPLAY 0.659574 (-3440 2910);
PAINT MONO (-3440 2910);
DISPLAY INVISIBLE (-3440 2910);
FORCEPROP 1 LASTPIN (-3450 2900) BN 24
J 0
(-3462 2908);
DISPLAY 0.489362 (-3462 2908);
PAINT GREEN (-3462 2908);
FORCEPROP 2 LAST CDS_LIB mstr_standard
J 0
(-3400 2900);
DISPLAY 0.723404 (-3400 2900);
PAINT MONO (-3400 2900);
DISPLAY INVISIBLE (-3400 2900);
FORCEPROP 1 LAST BODY_TYPE PLUMBING
J 0
(-3400 2950);
DISPLAY 0.872340 (-3400 2950);
PAINT GREEN (-3400 2950);
DISPLAY INVISIBLE (-3400 2950);
FORCEPROP 1 LAST HDL_TAP TRUE
J 0
(-3075 2775);
DISPLAY 0.872340 (-3075 2775);
DISPLAY INVISIBLE (-3075 2775);
FORCEPROP 1 LAST PATH I219
J 0
(-3402 2900);
DISPLAY 0.872340 (-3402 2900);
PAINT GREEN (-3402 2900);
DISPLAY INVISIBLE (-3402 2900);
FORCEADD TAP..1
(-3400 2850);
FORCEPROP 3 LASTPIN (-3450 2850) SIG_NAME M_E_CPU0_SB_DQ<25>
J 0
(-3440 2860);
DISPLAY 0.659574 (-3440 2860);
PAINT MONO (-3440 2860);
DISPLAY INVISIBLE (-3440 2860);
FORCEPROP 1 LASTPIN (-3450 2850) BN 25
J 0
(-3462 2858);
DISPLAY 0.489362 (-3462 2858);
PAINT GREEN (-3462 2858);
FORCEPROP 2 LAST CDS_LIB mstr_standard
J 0
(-3400 2850);
DISPLAY 0.723404 (-3400 2850);
PAINT MONO (-3400 2850);
DISPLAY INVISIBLE (-3400 2850);
FORCEPROP 1 LAST BODY_TYPE PLUMBING
J 0
(-3400 2900);
DISPLAY 0.872340 (-3400 2900);
PAINT GREEN (-3400 2900);
DISPLAY INVISIBLE (-3400 2900);
FORCEPROP 1 LAST HDL_TAP TRUE
J 0
(-3075 2725);
DISPLAY 0.872340 (-3075 2725);
DISPLAY INVISIBLE (-3075 2725);
FORCEPROP 1 LAST PATH I220
J 0
(-3402 2850);
DISPLAY 0.872340 (-3402 2850);
PAINT GREEN (-3402 2850);
DISPLAY INVISIBLE (-3402 2850);
FORCEADD TAP..1
(-3400 2800);
FORCEPROP 3 LASTPIN (-3450 2800) SIG_NAME M_E_CPU0_SB_DQ<26>
J 0
(-3440 2810);
DISPLAY 0.659574 (-3440 2810);
PAINT MONO (-3440 2810);
DISPLAY INVISIBLE (-3440 2810);
FORCEPROP 1 LASTPIN (-3450 2800) BN 26
J 0
(-3462 2808);
DISPLAY 0.489362 (-3462 2808);
PAINT GREEN (-3462 2808);
FORCEPROP 2 LAST CDS_LIB mstr_standard
J 0
(-3400 2800);
DISPLAY 0.723404 (-3400 2800);
PAINT MONO (-3400 2800);
DISPLAY INVISIBLE (-3400 2800);
FORCEPROP 1 LAST BODY_TYPE PLUMBING
J 0
(-3400 2850);
DISPLAY 0.872340 (-3400 2850);
PAINT GREEN (-3400 2850);
DISPLAY INVISIBLE (-3400 2850);
FORCEPROP 1 LAST HDL_TAP TRUE
J 0
(-3075 2675);
DISPLAY 0.872340 (-3075 2675);
DISPLAY INVISIBLE (-3075 2675);
FORCEPROP 1 LAST PATH I221
J 0
(-3402 2800);
DISPLAY 0.872340 (-3402 2800);
PAINT GREEN (-3402 2800);
DISPLAY INVISIBLE (-3402 2800);
FORCEADD TAP..1
(-3400 2750);
FORCEPROP 3 LASTPIN (-3450 2750) SIG_NAME M_E_CPU0_SB_DQ<27>
J 0
(-3440 2760);
DISPLAY 0.659574 (-3440 2760);
PAINT MONO (-3440 2760);
DISPLAY INVISIBLE (-3440 2760);
FORCEPROP 1 LASTPIN (-3450 2750) BN 27
J 0
(-3462 2758);
DISPLAY 0.489362 (-3462 2758);
PAINT GREEN (-3462 2758);
FORCEPROP 2 LAST CDS_LIB mstr_standard
J 0
(-3400 2750);
DISPLAY 0.723404 (-3400 2750);
PAINT MONO (-3400 2750);
DISPLAY INVISIBLE (-3400 2750);
FORCEPROP 1 LAST BODY_TYPE PLUMBING
J 0
(-3400 2800);
DISPLAY 0.872340 (-3400 2800);
PAINT GREEN (-3400 2800);
DISPLAY INVISIBLE (-3400 2800);
FORCEPROP 1 LAST HDL_TAP TRUE
J 0
(-3075 2625);
DISPLAY 0.872340 (-3075 2625);
DISPLAY INVISIBLE (-3075 2625);
FORCEPROP 1 LAST PATH I222
J 0
(-3402 2750);
DISPLAY 0.872340 (-3402 2750);
PAINT GREEN (-3402 2750);
DISPLAY INVISIBLE (-3402 2750);
FORCEADD TAP..1
(-3400 2700);
FORCEPROP 3 LASTPIN (-3450 2700) SIG_NAME M_E_CPU0_SB_DQ<28>
J 0
(-3440 2710);
DISPLAY 0.659574 (-3440 2710);
PAINT MONO (-3440 2710);
DISPLAY INVISIBLE (-3440 2710);
FORCEPROP 1 LASTPIN (-3450 2700) BN 28
J 0
(-3462 2708);
DISPLAY 0.489362 (-3462 2708);
PAINT GREEN (-3462 2708);
FORCEPROP 2 LAST CDS_LIB mstr_standard
J 0
(-3400 2700);
DISPLAY 0.723404 (-3400 2700);
PAINT MONO (-3400 2700);
DISPLAY INVISIBLE (-3400 2700);
FORCEPROP 1 LAST BODY_TYPE PLUMBING
J 0
(-3400 2750);
DISPLAY 0.872340 (-3400 2750);
PAINT GREEN (-3400 2750);
DISPLAY INVISIBLE (-3400 2750);
FORCEPROP 1 LAST HDL_TAP TRUE
J 0
(-3075 2575);
DISPLAY 0.872340 (-3075 2575);
DISPLAY INVISIBLE (-3075 2575);
FORCEPROP 1 LAST PATH I223
J 0
(-3402 2700);
DISPLAY 0.872340 (-3402 2700);
PAINT GREEN (-3402 2700);
DISPLAY INVISIBLE (-3402 2700);
FORCEADD TAP..1
(-3400 2650);
FORCEPROP 3 LASTPIN (-3450 2650) SIG_NAME M_E_CPU0_SB_DQ<29>
J 0
(-3440 2660);
DISPLAY 0.659574 (-3440 2660);
PAINT MONO (-3440 2660);
DISPLAY INVISIBLE (-3440 2660);
FORCEPROP 1 LASTPIN (-3450 2650) BN 29
J 0
(-3462 2658);
DISPLAY 0.489362 (-3462 2658);
PAINT GREEN (-3462 2658);
FORCEPROP 2 LAST CDS_LIB mstr_standard
J 0
(-3400 2650);
DISPLAY 0.723404 (-3400 2650);
PAINT MONO (-3400 2650);
DISPLAY INVISIBLE (-3400 2650);
FORCEPROP 1 LAST BODY_TYPE PLUMBING
J 0
(-3400 2700);
DISPLAY 0.872340 (-3400 2700);
PAINT GREEN (-3400 2700);
DISPLAY INVISIBLE (-3400 2700);
FORCEPROP 1 LAST HDL_TAP TRUE
J 0
(-3075 2525);
DISPLAY 0.872340 (-3075 2525);
DISPLAY INVISIBLE (-3075 2525);
FORCEPROP 1 LAST PATH I224
J 0
(-3402 2650);
DISPLAY 0.872340 (-3402 2650);
PAINT GREEN (-3402 2650);
DISPLAY INVISIBLE (-3402 2650);
FORCEADD TAP..1
(-3400 2600);
FORCEPROP 3 LASTPIN (-3450 2600) SIG_NAME M_E_CPU0_SB_DQ<30>
J 0
(-3440 2610);
DISPLAY 0.659574 (-3440 2610);
PAINT MONO (-3440 2610);
DISPLAY INVISIBLE (-3440 2610);
FORCEPROP 1 LASTPIN (-3450 2600) BN 30
J 0
(-3462 2608);
DISPLAY 0.489362 (-3462 2608);
PAINT GREEN (-3462 2608);
FORCEPROP 2 LAST CDS_LIB mstr_standard
J 0
(-3400 2600);
DISPLAY 0.723404 (-3400 2600);
PAINT MONO (-3400 2600);
DISPLAY INVISIBLE (-3400 2600);
FORCEPROP 1 LAST BODY_TYPE PLUMBING
J 0
(-3400 2650);
DISPLAY 0.872340 (-3400 2650);
PAINT GREEN (-3400 2650);
DISPLAY INVISIBLE (-3400 2650);
FORCEPROP 1 LAST HDL_TAP TRUE
J 0
(-3075 2475);
DISPLAY 0.872340 (-3075 2475);
DISPLAY INVISIBLE (-3075 2475);
FORCEPROP 1 LAST PATH I225
J 0
(-3402 2600);
DISPLAY 0.872340 (-3402 2600);
PAINT GREEN (-3402 2600);
DISPLAY INVISIBLE (-3402 2600);
FORCEADD TAP..1
(-3400 2450);
FORCEPROP 3 LASTPIN (-3450 2450) SIG_NAME M_E_CPU0_SA_CB<0>
J 0
(-3440 2460);
DISPLAY 0.659574 (-3440 2460);
PAINT MONO (-3440 2460);
DISPLAY INVISIBLE (-3440 2460);
FORCEPROP 1 LASTPIN (-3450 2450) BN 0
J 0
(-3462 2458);
DISPLAY 0.489362 (-3462 2458);
PAINT GREEN (-3462 2458);
FORCEPROP 2 LAST CDS_LIB mstr_standard
J 2
(-3400 2450);
DISPLAY 0.723404 (-3400 2450);
PAINT MONO (-3400 2450);
DISPLAY INVISIBLE (-3400 2450);
FORCEPROP 1 LAST BODY_TYPE PLUMBING
J 0
(-3400 2500);
DISPLAY 0.872340 (-3400 2500);
PAINT GREEN (-3400 2500);
DISPLAY INVISIBLE (-3400 2500);
FORCEPROP 1 LAST HDL_TAP TRUE
J 0
(-3075 2325);
DISPLAY 0.872340 (-3075 2325);
DISPLAY INVISIBLE (-3075 2325);
FORCEPROP 1 LAST PATH I226
J 0
(-3402 2450);
DISPLAY 0.872340 (-3402 2450);
PAINT GREEN (-3402 2450);
DISPLAY INVISIBLE (-3402 2450);
FORCEADD TAP..1
(-3400 2550);
FORCEPROP 3 LASTPIN (-3450 2550) SIG_NAME M_E_CPU0_SB_DQ<31>
J 0
(-3440 2560);
DISPLAY 0.659574 (-3440 2560);
PAINT MONO (-3440 2560);
DISPLAY INVISIBLE (-3440 2560);
FORCEPROP 1 LASTPIN (-3450 2550) BN 31
J 0
(-3462 2558);
DISPLAY 0.489362 (-3462 2558);
PAINT GREEN (-3462 2558);
FORCEPROP 2 LAST CDS_LIB mstr_standard
J 0
(-3400 2550);
DISPLAY 0.723404 (-3400 2550);
PAINT MONO (-3400 2550);
DISPLAY INVISIBLE (-3400 2550);
FORCEPROP 1 LAST BODY_TYPE PLUMBING
J 0
(-3400 2600);
DISPLAY 0.872340 (-3400 2600);
PAINT GREEN (-3400 2600);
DISPLAY INVISIBLE (-3400 2600);
FORCEPROP 1 LAST HDL_TAP TRUE
J 0
(-3075 2425);
DISPLAY 0.872340 (-3075 2425);
DISPLAY INVISIBLE (-3075 2425);
FORCEPROP 1 LAST PATH I227
J 0
(-3402 2550);
DISPLAY 0.872340 (-3402 2550);
PAINT GREEN (-3402 2550);
DISPLAY INVISIBLE (-3402 2550);
FORCEADD TAP..1
(-3400 2350);
FORCEPROP 3 LASTPIN (-3450 2350) SIG_NAME M_E_CPU0_SA_CB<2>
J 0
(-3440 2360);
DISPLAY 0.659574 (-3440 2360);
PAINT MONO (-3440 2360);
DISPLAY INVISIBLE (-3440 2360);
FORCEPROP 1 LASTPIN (-3450 2350) BN 2
J 0
(-3462 2358);
DISPLAY 0.489362 (-3462 2358);
PAINT GREEN (-3462 2358);
FORCEPROP 2 LAST CDS_LIB mstr_standard
J 2
(-3400 2350);
DISPLAY 0.723404 (-3400 2350);
PAINT MONO (-3400 2350);
DISPLAY INVISIBLE (-3400 2350);
FORCEPROP 1 LAST BODY_TYPE PLUMBING
J 0
(-3400 2400);
DISPLAY 0.872340 (-3400 2400);
PAINT GREEN (-3400 2400);
DISPLAY INVISIBLE (-3400 2400);
FORCEPROP 1 LAST HDL_TAP TRUE
J 0
(-3075 2225);
DISPLAY 0.872340 (-3075 2225);
DISPLAY INVISIBLE (-3075 2225);
FORCEPROP 1 LAST PATH I228
J 0
(-3402 2350);
DISPLAY 0.872340 (-3402 2350);
PAINT GREEN (-3402 2350);
DISPLAY INVISIBLE (-3402 2350);
FORCEADD TAP..1
(-3400 2400);
FORCEPROP 3 LASTPIN (-3450 2400) SIG_NAME M_E_CPU0_SA_CB<1>
J 0
(-3440 2410);
DISPLAY 0.659574 (-3440 2410);
PAINT MONO (-3440 2410);
DISPLAY INVISIBLE (-3440 2410);
FORCEPROP 1 LASTPIN (-3450 2400) BN 1
J 0
(-3462 2408);
DISPLAY 0.489362 (-3462 2408);
PAINT GREEN (-3462 2408);
FORCEPROP 2 LAST CDS_LIB mstr_standard
J 2
(-3400 2400);
DISPLAY 0.723404 (-3400 2400);
PAINT MONO (-3400 2400);
DISPLAY INVISIBLE (-3400 2400);
FORCEPROP 1 LAST BODY_TYPE PLUMBING
J 0
(-3400 2450);
DISPLAY 0.872340 (-3400 2450);
PAINT GREEN (-3400 2450);
DISPLAY INVISIBLE (-3400 2450);
FORCEPROP 1 LAST HDL_TAP TRUE
J 0
(-3075 2275);
DISPLAY 0.872340 (-3075 2275);
DISPLAY INVISIBLE (-3075 2275);
FORCEPROP 1 LAST PATH I229
J 0
(-3402 2400);
DISPLAY 0.872340 (-3402 2400);
PAINT GREEN (-3402 2400);
DISPLAY INVISIBLE (-3402 2400);
FORCEADD TAP..1
(-3400 2250);
FORCEPROP 3 LASTPIN (-3450 2250) SIG_NAME M_E_CPU0_SA_CB<4>
J 0
(-3440 2260);
DISPLAY 0.659574 (-3440 2260);
PAINT MONO (-3440 2260);
DISPLAY INVISIBLE (-3440 2260);
FORCEPROP 1 LASTPIN (-3450 2250) BN 4
J 0
(-3462 2258);
DISPLAY 0.489362 (-3462 2258);
PAINT GREEN (-3462 2258);
FORCEPROP 2 LAST CDS_LIB mstr_standard
J 2
(-3400 2250);
DISPLAY 0.723404 (-3400 2250);
PAINT MONO (-3400 2250);
DISPLAY INVISIBLE (-3400 2250);
FORCEPROP 1 LAST BODY_TYPE PLUMBING
J 0
(-3400 2300);
DISPLAY 0.872340 (-3400 2300);
PAINT GREEN (-3400 2300);
DISPLAY INVISIBLE (-3400 2300);
FORCEPROP 1 LAST HDL_TAP TRUE
J 0
(-3075 2125);
DISPLAY 0.872340 (-3075 2125);
DISPLAY INVISIBLE (-3075 2125);
FORCEPROP 1 LAST PATH I230
J 0
(-3402 2250);
DISPLAY 0.872340 (-3402 2250);
PAINT GREEN (-3402 2250);
DISPLAY INVISIBLE (-3402 2250);
FORCEADD TAP..1
(-3400 2300);
FORCEPROP 3 LASTPIN (-3450 2300) SIG_NAME M_E_CPU0_SA_CB<3>
J 0
(-3440 2310);
DISPLAY 0.659574 (-3440 2310);
PAINT MONO (-3440 2310);
DISPLAY INVISIBLE (-3440 2310);
FORCEPROP 1 LASTPIN (-3450 2300) BN 3
J 0
(-3462 2308);
DISPLAY 0.489362 (-3462 2308);
PAINT GREEN (-3462 2308);
FORCEPROP 2 LAST CDS_LIB mstr_standard
J 2
(-3400 2300);
DISPLAY 0.723404 (-3400 2300);
PAINT MONO (-3400 2300);
DISPLAY INVISIBLE (-3400 2300);
FORCEPROP 1 LAST BODY_TYPE PLUMBING
J 0
(-3400 2350);
DISPLAY 0.872340 (-3400 2350);
PAINT GREEN (-3400 2350);
DISPLAY INVISIBLE (-3400 2350);
FORCEPROP 1 LAST HDL_TAP TRUE
J 0
(-3075 2175);
DISPLAY 0.872340 (-3075 2175);
DISPLAY INVISIBLE (-3075 2175);
FORCEPROP 1 LAST PATH I231
J 0
(-3402 2300);
DISPLAY 0.872340 (-3402 2300);
PAINT GREEN (-3402 2300);
DISPLAY INVISIBLE (-3402 2300);
FORCEADD TAP..1
(-3400 2200);
FORCEPROP 3 LASTPIN (-3450 2200) SIG_NAME M_E_CPU0_SA_CB<5>
J 0
(-3440 2210);
DISPLAY 0.659574 (-3440 2210);
PAINT MONO (-3440 2210);
DISPLAY INVISIBLE (-3440 2210);
FORCEPROP 1 LASTPIN (-3450 2200) BN 5
J 0
(-3462 2208);
DISPLAY 0.489362 (-3462 2208);
PAINT GREEN (-3462 2208);
FORCEPROP 2 LAST CDS_LIB mstr_standard
J 2
(-3400 2200);
DISPLAY 0.723404 (-3400 2200);
PAINT MONO (-3400 2200);
DISPLAY INVISIBLE (-3400 2200);
FORCEPROP 1 LAST BODY_TYPE PLUMBING
J 0
(-3400 2250);
DISPLAY 0.872340 (-3400 2250);
PAINT GREEN (-3400 2250);
DISPLAY INVISIBLE (-3400 2250);
FORCEPROP 1 LAST HDL_TAP TRUE
J 0
(-3075 2075);
DISPLAY 0.872340 (-3075 2075);
DISPLAY INVISIBLE (-3075 2075);
FORCEPROP 1 LAST PATH I232
J 0
(-3402 2200);
DISPLAY 0.872340 (-3402 2200);
PAINT GREEN (-3402 2200);
DISPLAY INVISIBLE (-3402 2200);
FORCEADD TAP..1
(-3400 2150);
FORCEPROP 3 LASTPIN (-3450 2150) SIG_NAME M_E_CPU0_SA_CB<6>
J 0
(-3440 2160);
DISPLAY 0.659574 (-3440 2160);
PAINT MONO (-3440 2160);
DISPLAY INVISIBLE (-3440 2160);
FORCEPROP 1 LASTPIN (-3450 2150) BN 6
J 0
(-3462 2158);
DISPLAY 0.489362 (-3462 2158);
PAINT GREEN (-3462 2158);
FORCEPROP 2 LAST CDS_LIB mstr_standard
J 2
(-3400 2150);
DISPLAY 0.723404 (-3400 2150);
PAINT MONO (-3400 2150);
DISPLAY INVISIBLE (-3400 2150);
FORCEPROP 1 LAST BODY_TYPE PLUMBING
J 0
(-3400 2200);
DISPLAY 0.872340 (-3400 2200);
PAINT GREEN (-3400 2200);
DISPLAY INVISIBLE (-3400 2200);
FORCEPROP 1 LAST HDL_TAP TRUE
J 0
(-3075 2025);
DISPLAY 0.872340 (-3075 2025);
DISPLAY INVISIBLE (-3075 2025);
FORCEPROP 1 LAST PATH I233
J 0
(-3402 2150);
DISPLAY 0.872340 (-3402 2150);
PAINT GREEN (-3402 2150);
DISPLAY INVISIBLE (-3402 2150);
FORCEADD TAP..1
(-3400 2100);
FORCEPROP 3 LASTPIN (-3450 2100) SIG_NAME M_E_CPU0_SA_CB<7>
J 0
(-3440 2110);
DISPLAY 0.659574 (-3440 2110);
PAINT MONO (-3440 2110);
DISPLAY INVISIBLE (-3440 2110);
FORCEPROP 1 LASTPIN (-3450 2100) BN 7
J 0
(-3462 2108);
DISPLAY 0.489362 (-3462 2108);
PAINT GREEN (-3462 2108);
FORCEPROP 2 LAST CDS_LIB mstr_standard
J 2
(-3400 2100);
DISPLAY 0.723404 (-3400 2100);
PAINT MONO (-3400 2100);
DISPLAY INVISIBLE (-3400 2100);
FORCEPROP 1 LAST BODY_TYPE PLUMBING
J 0
(-3400 2150);
DISPLAY 0.872340 (-3400 2150);
PAINT GREEN (-3400 2150);
DISPLAY INVISIBLE (-3400 2150);
FORCEPROP 1 LAST HDL_TAP TRUE
J 0
(-3075 1975);
DISPLAY 0.872340 (-3075 1975);
DISPLAY INVISIBLE (-3075 1975);
FORCEPROP 1 LAST PATH I234
J 0
(-3402 2100);
DISPLAY 0.872340 (-3402 2100);
PAINT GREEN (-3402 2100);
DISPLAY INVISIBLE (-3402 2100);
FORCEADD OFFPAGE..6
R 2
(-2800 2050);
FORCEPROP 2 LAST $XR0 90 
J 0
(-2586 2050);
DISPLAY 0.638298 (-2586 2050);
PAINT MONO (-2586 2050);
FORCEPROP 2 LAST CDS_LIB mstr_standard
J 2
(-2800 2050);
DISPLAY 0.723404 (-2800 2050);
PAINT MONO (-2800 2050);
DISPLAY INVISIBLE (-2800 2050);
FORCEPROP 1 LAST OFFPAGE TRUE
J 2
(-3125 1925);
DISPLAY 0.872340 (-3125 1925);
PAINT GREEN (-3125 1925);
DISPLAY INVISIBLE (-3125 1925);
FORCEPROP 1 LAST COMMENT_BODY TRUE
J 2
(-2900 1975);
DISPLAY 0.872340 (-2900 1975);
PAINT GREEN (-2900 1975);
DISPLAY INVISIBLE (-2900 1975);
FORCEPROP 2 LAST PATH I235
J 0
(-2575 2100);
DISPLAY 1.021277 (-2575 2100);
DISPLAY INVISIBLE (-2575 2100);
FORCEADD TAP..1
(-3400 1950);
FORCEPROP 3 LASTPIN (-3450 1950) SIG_NAME M_E_CPU0_SB_CB<1>
J 0
(-3440 1960);
DISPLAY 0.659574 (-3440 1960);
PAINT MONO (-3440 1960);
DISPLAY INVISIBLE (-3440 1960);
FORCEPROP 1 LASTPIN (-3450 1950) BN 1
J 0
(-3462 1958);
DISPLAY 0.489362 (-3462 1958);
PAINT GREEN (-3462 1958);
FORCEPROP 2 LAST CDS_LIB mstr_standard
J 2
(-3400 1950);
DISPLAY 0.723404 (-3400 1950);
PAINT MONO (-3400 1950);
DISPLAY INVISIBLE (-3400 1950);
FORCEPROP 1 LAST BODY_TYPE PLUMBING
J 0
(-3400 2000);
DISPLAY 0.872340 (-3400 2000);
PAINT GREEN (-3400 2000);
DISPLAY INVISIBLE (-3400 2000);
FORCEPROP 1 LAST HDL_TAP TRUE
J 0
(-3075 1825);
DISPLAY 0.872340 (-3075 1825);
DISPLAY INVISIBLE (-3075 1825);
FORCEPROP 1 LAST PATH I236
J 0
(-3402 1950);
DISPLAY 0.872340 (-3402 1950);
PAINT GREEN (-3402 1950);
DISPLAY INVISIBLE (-3402 1950);
FORCEADD TAP..1
(-3400 2000);
FORCEPROP 3 LASTPIN (-3450 2000) SIG_NAME M_E_CPU0_SB_CB<0>
J 0
(-3440 2010);
DISPLAY 0.659574 (-3440 2010);
PAINT MONO (-3440 2010);
DISPLAY INVISIBLE (-3440 2010);
FORCEPROP 1 LASTPIN (-3450 2000) BN 0
J 0
(-3462 2008);
DISPLAY 0.489362 (-3462 2008);
PAINT GREEN (-3462 2008);
FORCEPROP 2 LAST CDS_LIB mstr_standard
J 2
(-3400 2000);
DISPLAY 0.723404 (-3400 2000);
PAINT MONO (-3400 2000);
DISPLAY INVISIBLE (-3400 2000);
FORCEPROP 1 LAST BODY_TYPE PLUMBING
J 0
(-3400 2050);
DISPLAY 0.872340 (-3400 2050);
PAINT GREEN (-3400 2050);
DISPLAY INVISIBLE (-3400 2050);
FORCEPROP 1 LAST HDL_TAP TRUE
J 0
(-3075 1875);
DISPLAY 0.872340 (-3075 1875);
DISPLAY INVISIBLE (-3075 1875);
FORCEPROP 1 LAST PATH I237
J 0
(-3402 2000);
DISPLAY 0.872340 (-3402 2000);
PAINT GREEN (-3402 2000);
DISPLAY INVISIBLE (-3402 2000);
FORCEADD TAP..1
(-3400 1800);
FORCEPROP 3 LASTPIN (-3450 1800) SIG_NAME M_E_CPU0_SB_CB<4>
J 0
(-3440 1810);
DISPLAY 0.659574 (-3440 1810);
PAINT MONO (-3440 1810);
DISPLAY INVISIBLE (-3440 1810);
FORCEPROP 1 LASTPIN (-3450 1800) BN 4
J 0
(-3462 1808);
DISPLAY 0.489362 (-3462 1808);
PAINT GREEN (-3462 1808);
FORCEPROP 2 LAST CDS_LIB mstr_standard
J 2
(-3400 1800);
DISPLAY 0.723404 (-3400 1800);
PAINT MONO (-3400 1800);
DISPLAY INVISIBLE (-3400 1800);
FORCEPROP 1 LAST BODY_TYPE PLUMBING
J 0
(-3400 1850);
DISPLAY 0.872340 (-3400 1850);
PAINT GREEN (-3400 1850);
DISPLAY INVISIBLE (-3400 1850);
FORCEPROP 1 LAST HDL_TAP TRUE
J 0
(-3075 1675);
DISPLAY 0.872340 (-3075 1675);
DISPLAY INVISIBLE (-3075 1675);
FORCEPROP 1 LAST PATH I238
J 0
(-3402 1800);
DISPLAY 0.872340 (-3402 1800);
PAINT GREEN (-3402 1800);
DISPLAY INVISIBLE (-3402 1800);
FORCEADD TAP..1
(-3400 1900);
FORCEPROP 3 LASTPIN (-3450 1900) SIG_NAME M_E_CPU0_SB_CB<2>
J 0
(-3440 1910);
DISPLAY 0.659574 (-3440 1910);
PAINT MONO (-3440 1910);
DISPLAY INVISIBLE (-3440 1910);
FORCEPROP 1 LASTPIN (-3450 1900) BN 2
J 0
(-3462 1908);
DISPLAY 0.489362 (-3462 1908);
PAINT GREEN (-3462 1908);
FORCEPROP 2 LAST CDS_LIB mstr_standard
J 2
(-3400 1900);
DISPLAY 0.723404 (-3400 1900);
PAINT MONO (-3400 1900);
DISPLAY INVISIBLE (-3400 1900);
FORCEPROP 1 LAST BODY_TYPE PLUMBING
J 0
(-3400 1950);
DISPLAY 0.872340 (-3400 1950);
PAINT GREEN (-3400 1950);
DISPLAY INVISIBLE (-3400 1950);
FORCEPROP 1 LAST HDL_TAP TRUE
J 0
(-3075 1775);
DISPLAY 0.872340 (-3075 1775);
DISPLAY INVISIBLE (-3075 1775);
FORCEPROP 1 LAST PATH I239
J 0
(-3402 1900);
DISPLAY 0.872340 (-3402 1900);
PAINT GREEN (-3402 1900);
DISPLAY INVISIBLE (-3402 1900);
FORCEADD TAP..1
(-3400 1850);
FORCEPROP 3 LASTPIN (-3450 1850) SIG_NAME M_E_CPU0_SB_CB<3>
J 0
(-3440 1860);
DISPLAY 0.659574 (-3440 1860);
PAINT MONO (-3440 1860);
DISPLAY INVISIBLE (-3440 1860);
FORCEPROP 1 LASTPIN (-3450 1850) BN 3
J 0
(-3462 1858);
DISPLAY 0.489362 (-3462 1858);
PAINT GREEN (-3462 1858);
FORCEPROP 2 LAST CDS_LIB mstr_standard
J 2
(-3400 1850);
DISPLAY 0.723404 (-3400 1850);
PAINT MONO (-3400 1850);
DISPLAY INVISIBLE (-3400 1850);
FORCEPROP 1 LAST BODY_TYPE PLUMBING
J 0
(-3400 1900);
DISPLAY 0.872340 (-3400 1900);
PAINT GREEN (-3400 1900);
DISPLAY INVISIBLE (-3400 1900);
FORCEPROP 1 LAST HDL_TAP TRUE
J 0
(-3075 1725);
DISPLAY 0.872340 (-3075 1725);
DISPLAY INVISIBLE (-3075 1725);
FORCEPROP 1 LAST PATH I240
J 0
(-3402 1850);
DISPLAY 0.872340 (-3402 1850);
PAINT GREEN (-3402 1850);
DISPLAY INVISIBLE (-3402 1850);
FORCEADD TAP..1
(-3400 1700);
FORCEPROP 3 LASTPIN (-3450 1700) SIG_NAME M_E_CPU0_SB_CB<6>
J 0
(-3440 1710);
DISPLAY 0.659574 (-3440 1710);
PAINT MONO (-3440 1710);
DISPLAY INVISIBLE (-3440 1710);
FORCEPROP 1 LASTPIN (-3450 1700) BN 6
J 0
(-3462 1708);
DISPLAY 0.489362 (-3462 1708);
PAINT GREEN (-3462 1708);
FORCEPROP 2 LAST CDS_LIB mstr_standard
J 2
(-3400 1700);
DISPLAY 0.723404 (-3400 1700);
PAINT MONO (-3400 1700);
DISPLAY INVISIBLE (-3400 1700);
FORCEPROP 1 LAST BODY_TYPE PLUMBING
J 0
(-3400 1750);
DISPLAY 0.872340 (-3400 1750);
PAINT GREEN (-3400 1750);
DISPLAY INVISIBLE (-3400 1750);
FORCEPROP 1 LAST HDL_TAP TRUE
J 0
(-3075 1575);
DISPLAY 0.872340 (-3075 1575);
DISPLAY INVISIBLE (-3075 1575);
FORCEPROP 1 LAST PATH I241
J 0
(-3402 1700);
DISPLAY 0.872340 (-3402 1700);
PAINT GREEN (-3402 1700);
DISPLAY INVISIBLE (-3402 1700);
FORCEADD TAP..1
(-3400 1750);
FORCEPROP 3 LASTPIN (-3450 1750) SIG_NAME M_E_CPU0_SB_CB<5>
J 0
(-3440 1760);
DISPLAY 0.659574 (-3440 1760);
PAINT MONO (-3440 1760);
DISPLAY INVISIBLE (-3440 1760);
FORCEPROP 1 LASTPIN (-3450 1750) BN 5
J 0
(-3462 1758);
DISPLAY 0.489362 (-3462 1758);
PAINT GREEN (-3462 1758);
FORCEPROP 2 LAST CDS_LIB mstr_standard
J 2
(-3400 1750);
DISPLAY 0.723404 (-3400 1750);
PAINT MONO (-3400 1750);
DISPLAY INVISIBLE (-3400 1750);
FORCEPROP 1 LAST BODY_TYPE PLUMBING
J 0
(-3400 1800);
DISPLAY 0.872340 (-3400 1800);
PAINT GREEN (-3400 1800);
DISPLAY INVISIBLE (-3400 1800);
FORCEPROP 1 LAST HDL_TAP TRUE
J 0
(-3075 1625);
DISPLAY 0.872340 (-3075 1625);
DISPLAY INVISIBLE (-3075 1625);
FORCEPROP 1 LAST PATH I242
J 0
(-3402 1750);
DISPLAY 0.872340 (-3402 1750);
PAINT GREEN (-3402 1750);
DISPLAY INVISIBLE (-3402 1750);
FORCEADD TAP..1
(-3400 1650);
FORCEPROP 3 LASTPIN (-3450 1650) SIG_NAME M_E_CPU0_SB_CB<7>
J 0
(-3440 1660);
DISPLAY 0.659574 (-3440 1660);
PAINT MONO (-3440 1660);
DISPLAY INVISIBLE (-3440 1660);
FORCEPROP 1 LASTPIN (-3450 1650) BN 7
J 0
(-3462 1658);
DISPLAY 0.489362 (-3462 1658);
PAINT GREEN (-3462 1658);
FORCEPROP 2 LAST CDS_LIB mstr_standard
J 2
(-3400 1650);
DISPLAY 0.723404 (-3400 1650);
PAINT MONO (-3400 1650);
DISPLAY INVISIBLE (-3400 1650);
FORCEPROP 1 LAST BODY_TYPE PLUMBING
J 0
(-3400 1700);
DISPLAY 0.872340 (-3400 1700);
PAINT GREEN (-3400 1700);
DISPLAY INVISIBLE (-3400 1700);
FORCEPROP 1 LAST HDL_TAP TRUE
J 0
(-3075 1525);
DISPLAY 0.872340 (-3075 1525);
DISPLAY INVISIBLE (-3075 1525);
FORCEPROP 1 LAST PATH I243
J 0
(-3402 1650);
DISPLAY 0.872340 (-3402 1650);
PAINT GREEN (-3402 1650);
DISPLAY INVISIBLE (-3402 1650);
FORCEADD TAP..1
R 2
(-5825 6050);
FORCEPROP 3 LASTPIN (-5775 6050) SIG_NAME M_E_CPU0_SA_DQS_DP<0>
J 0
(-5765 6060);
DISPLAY 0.659574 (-5765 6060);
PAINT MONO (-5765 6060);
DISPLAY INVISIBLE (-5765 6060);
FORCEPROP 1 LASTPIN (-5775 6050) BN 0
J 2
(-5763 6058);
DISPLAY 0.489362 (-5763 6058);
PAINT GREEN (-5763 6058);
FORCEPROP 2 LAST CDS_LIB mstr_standard
J 2
(-5825 6050);
DISPLAY 0.723404 (-5825 6050);
PAINT MONO (-5825 6050);
DISPLAY INVISIBLE (-5825 6050);
FORCEPROP 1 LAST BODY_TYPE PLUMBING
J 2
(-5825 6100);
DISPLAY 0.872340 (-5825 6100);
PAINT GREEN (-5825 6100);
DISPLAY INVISIBLE (-5825 6100);
FORCEPROP 1 LAST HDL_TAP TRUE
J 2
(-6150 5925);
DISPLAY 0.872340 (-6150 5925);
DISPLAY INVISIBLE (-6150 5925);
FORCEPROP 1 LAST PATH I244
J 2
(-5823 6050);
DISPLAY 0.872340 (-5823 6050);
PAINT GREEN (-5823 6050);
DISPLAY INVISIBLE (-5823 6050);
FORCEADD TAP..1
R 2
(-5825 5950);
FORCEPROP 3 LASTPIN (-5775 5950) SIG_NAME M_E_CPU0_SA_DQS_DP<1>
J 0
(-5765 5960);
DISPLAY 0.659574 (-5765 5960);
PAINT MONO (-5765 5960);
DISPLAY INVISIBLE (-5765 5960);
FORCEPROP 1 LASTPIN (-5775 5950) BN 1
J 2
(-5763 5958);
DISPLAY 0.489362 (-5763 5958);
PAINT GREEN (-5763 5958);
FORCEPROP 2 LAST CDS_LIB mstr_standard
J 2
(-5825 5950);
DISPLAY 0.723404 (-5825 5950);
PAINT MONO (-5825 5950);
DISPLAY INVISIBLE (-5825 5950);
FORCEPROP 1 LAST BODY_TYPE PLUMBING
J 2
(-5825 6000);
DISPLAY 0.872340 (-5825 6000);
PAINT GREEN (-5825 6000);
DISPLAY INVISIBLE (-5825 6000);
FORCEPROP 1 LAST HDL_TAP TRUE
J 2
(-6150 5825);
DISPLAY 0.872340 (-6150 5825);
DISPLAY INVISIBLE (-6150 5825);
FORCEPROP 1 LAST PATH I245
J 2
(-5823 5950);
DISPLAY 0.872340 (-5823 5950);
PAINT GREEN (-5823 5950);
DISPLAY INVISIBLE (-5823 5950);
FORCEADD TAP..1
R 2
(-5825 5750);
FORCEPROP 3 LASTPIN (-5775 5750) SIG_NAME M_E_CPU0_SA_DQS_DP<3>
J 0
(-5765 5760);
DISPLAY 0.659574 (-5765 5760);
PAINT MONO (-5765 5760);
DISPLAY INVISIBLE (-5765 5760);
FORCEPROP 1 LASTPIN (-5775 5750) BN 3
J 2
(-5763 5758);
DISPLAY 0.489362 (-5763 5758);
PAINT GREEN (-5763 5758);
FORCEPROP 2 LAST CDS_LIB mstr_standard
J 2
(-5825 5750);
DISPLAY 0.723404 (-5825 5750);
PAINT MONO (-5825 5750);
DISPLAY INVISIBLE (-5825 5750);
FORCEPROP 1 LAST BODY_TYPE PLUMBING
J 2
(-5825 5800);
DISPLAY 0.872340 (-5825 5800);
PAINT GREEN (-5825 5800);
DISPLAY INVISIBLE (-5825 5800);
FORCEPROP 1 LAST HDL_TAP TRUE
J 2
(-6150 5625);
DISPLAY 0.872340 (-6150 5625);
DISPLAY INVISIBLE (-6150 5625);
FORCEPROP 1 LAST PATH I246
J 2
(-5823 5750);
DISPLAY 0.872340 (-5823 5750);
PAINT GREEN (-5823 5750);
DISPLAY INVISIBLE (-5823 5750);
FORCEADD TAP..1
R 2
(-5825 5850);
FORCEPROP 3 LASTPIN (-5775 5850) SIG_NAME M_E_CPU0_SA_DQS_DP<2>
J 0
(-5765 5860);
DISPLAY 0.659574 (-5765 5860);
PAINT MONO (-5765 5860);
DISPLAY INVISIBLE (-5765 5860);
FORCEPROP 1 LASTPIN (-5775 5850) BN 2
J 2
(-5763 5858);
DISPLAY 0.489362 (-5763 5858);
PAINT GREEN (-5763 5858);
FORCEPROP 2 LAST CDS_LIB mstr_standard
J 2
(-5825 5850);
DISPLAY 0.723404 (-5825 5850);
PAINT MONO (-5825 5850);
DISPLAY INVISIBLE (-5825 5850);
FORCEPROP 1 LAST BODY_TYPE PLUMBING
J 2
(-5825 5900);
DISPLAY 0.872340 (-5825 5900);
PAINT GREEN (-5825 5900);
DISPLAY INVISIBLE (-5825 5900);
FORCEPROP 1 LAST HDL_TAP TRUE
J 2
(-6150 5725);
DISPLAY 0.872340 (-6150 5725);
DISPLAY INVISIBLE (-6150 5725);
FORCEPROP 1 LAST PATH I247
J 2
(-5823 5850);
DISPLAY 0.872340 (-5823 5850);
PAINT GREEN (-5823 5850);
DISPLAY INVISIBLE (-5823 5850);
FORCEADD TAP..1
R 2
(-5825 5650);
FORCEPROP 3 LASTPIN (-5775 5650) SIG_NAME M_E_CPU0_SA_DQS_DP<4>
J 0
(-5765 5660);
DISPLAY 0.659574 (-5765 5660);
PAINT MONO (-5765 5660);
DISPLAY INVISIBLE (-5765 5660);
FORCEPROP 1 LASTPIN (-5775 5650) BN 4
J 2
(-5763 5658);
DISPLAY 0.489362 (-5763 5658);
PAINT GREEN (-5763 5658);
FORCEPROP 2 LAST CDS_LIB mstr_standard
J 2
(-5825 5650);
DISPLAY 0.723404 (-5825 5650);
PAINT MONO (-5825 5650);
DISPLAY INVISIBLE (-5825 5650);
FORCEPROP 1 LAST BODY_TYPE PLUMBING
J 2
(-5825 5700);
DISPLAY 0.872340 (-5825 5700);
PAINT GREEN (-5825 5700);
DISPLAY INVISIBLE (-5825 5700);
FORCEPROP 1 LAST HDL_TAP TRUE
J 2
(-6150 5525);
DISPLAY 0.872340 (-6150 5525);
DISPLAY INVISIBLE (-6150 5525);
FORCEPROP 1 LAST PATH I248
J 2
(-5823 5650);
DISPLAY 0.872340 (-5823 5650);
PAINT GREEN (-5823 5650);
DISPLAY INVISIBLE (-5823 5650);
FORCEADD TAP..1
R 2
(-6025 6000);
FORCEPROP 3 LASTPIN (-5975 6000) SIG_NAME M_E_CPU0_SA_DQS_DN<0>
J 0
(-5965 6010);
DISPLAY 0.659574 (-5965 6010);
PAINT MONO (-5965 6010);
DISPLAY INVISIBLE (-5965 6010);
FORCEPROP 1 LASTPIN (-5975 6000) BN 0
J 2
(-5963 6008);
DISPLAY 0.489362 (-5963 6008);
PAINT GREEN (-5963 6008);
FORCEPROP 2 LAST CDS_LIB mstr_standard
J 2
(-6025 6000);
DISPLAY 0.723404 (-6025 6000);
PAINT MONO (-6025 6000);
DISPLAY INVISIBLE (-6025 6000);
FORCEPROP 1 LAST BODY_TYPE PLUMBING
J 2
(-6025 6050);
DISPLAY 0.872340 (-6025 6050);
PAINT GREEN (-6025 6050);
DISPLAY INVISIBLE (-6025 6050);
FORCEPROP 1 LAST HDL_TAP TRUE
J 2
(-6350 5875);
DISPLAY 0.872340 (-6350 5875);
DISPLAY INVISIBLE (-6350 5875);
FORCEPROP 1 LAST PATH I249
J 2
(-6023 6000);
DISPLAY 0.872340 (-6023 6000);
PAINT GREEN (-6023 6000);
DISPLAY INVISIBLE (-6023 6000);
FORCEADD TAP..1
R 2
(-6025 5900);
FORCEPROP 3 LASTPIN (-5975 5900) SIG_NAME M_E_CPU0_SA_DQS_DN<1>
J 0
(-5965 5910);
DISPLAY 0.659574 (-5965 5910);
PAINT MONO (-5965 5910);
DISPLAY INVISIBLE (-5965 5910);
FORCEPROP 1 LASTPIN (-5975 5900) BN 1
J 2
(-5963 5908);
DISPLAY 0.489362 (-5963 5908);
PAINT GREEN (-5963 5908);
FORCEPROP 2 LAST CDS_LIB mstr_standard
J 2
(-6025 5900);
DISPLAY 0.723404 (-6025 5900);
PAINT MONO (-6025 5900);
DISPLAY INVISIBLE (-6025 5900);
FORCEPROP 1 LAST BODY_TYPE PLUMBING
J 2
(-6025 5950);
DISPLAY 0.872340 (-6025 5950);
PAINT GREEN (-6025 5950);
DISPLAY INVISIBLE (-6025 5950);
FORCEPROP 1 LAST HDL_TAP TRUE
J 2
(-6350 5775);
DISPLAY 0.872340 (-6350 5775);
DISPLAY INVISIBLE (-6350 5775);
FORCEPROP 1 LAST PATH I250
J 2
(-6023 5900);
DISPLAY 0.872340 (-6023 5900);
PAINT GREEN (-6023 5900);
DISPLAY INVISIBLE (-6023 5900);
FORCEADD TAP..1
R 2
(-6025 5800);
FORCEPROP 3 LASTPIN (-5975 5800) SIG_NAME M_E_CPU0_SA_DQS_DN<2>
J 0
(-5965 5810);
DISPLAY 0.659574 (-5965 5810);
PAINT MONO (-5965 5810);
DISPLAY INVISIBLE (-5965 5810);
FORCEPROP 1 LASTPIN (-5975 5800) BN 2
J 2
(-5963 5808);
DISPLAY 0.489362 (-5963 5808);
PAINT GREEN (-5963 5808);
FORCEPROP 2 LAST CDS_LIB mstr_standard
J 2
(-6025 5800);
DISPLAY 0.723404 (-6025 5800);
PAINT MONO (-6025 5800);
DISPLAY INVISIBLE (-6025 5800);
FORCEPROP 1 LAST BODY_TYPE PLUMBING
J 2
(-6025 5850);
DISPLAY 0.872340 (-6025 5850);
PAINT GREEN (-6025 5850);
DISPLAY INVISIBLE (-6025 5850);
FORCEPROP 1 LAST HDL_TAP TRUE
J 2
(-6350 5675);
DISPLAY 0.872340 (-6350 5675);
DISPLAY INVISIBLE (-6350 5675);
FORCEPROP 1 LAST PATH I251
J 2
(-6023 5800);
DISPLAY 0.872340 (-6023 5800);
PAINT GREEN (-6023 5800);
DISPLAY INVISIBLE (-6023 5800);
FORCEADD TAP..1
R 2
(-6025 5700);
FORCEPROP 3 LASTPIN (-5975 5700) SIG_NAME M_E_CPU0_SA_DQS_DN<3>
J 0
(-5965 5710);
DISPLAY 0.659574 (-5965 5710);
PAINT MONO (-5965 5710);
DISPLAY INVISIBLE (-5965 5710);
FORCEPROP 1 LASTPIN (-5975 5700) BN 3
J 2
(-5963 5708);
DISPLAY 0.489362 (-5963 5708);
PAINT GREEN (-5963 5708);
FORCEPROP 2 LAST CDS_LIB mstr_standard
J 2
(-6025 5700);
DISPLAY 0.723404 (-6025 5700);
PAINT MONO (-6025 5700);
DISPLAY INVISIBLE (-6025 5700);
FORCEPROP 1 LAST BODY_TYPE PLUMBING
J 2
(-6025 5750);
DISPLAY 0.872340 (-6025 5750);
PAINT GREEN (-6025 5750);
DISPLAY INVISIBLE (-6025 5750);
FORCEPROP 1 LAST HDL_TAP TRUE
J 2
(-6350 5575);
DISPLAY 0.872340 (-6350 5575);
DISPLAY INVISIBLE (-6350 5575);
FORCEPROP 1 LAST PATH I252
J 2
(-6023 5700);
DISPLAY 0.872340 (-6023 5700);
PAINT GREEN (-6023 5700);
DISPLAY INVISIBLE (-6023 5700);
FORCEADD TAP..1
R 2
(-5825 5550);
FORCEPROP 3 LASTPIN (-5775 5550) SIG_NAME M_E_CPU0_SA_DQS_DP<5>
J 0
(-5765 5560);
DISPLAY 0.659574 (-5765 5560);
PAINT MONO (-5765 5560);
DISPLAY INVISIBLE (-5765 5560);
FORCEPROP 1 LASTPIN (-5775 5550) BN 5
J 2
(-5763 5558);
DISPLAY 0.489362 (-5763 5558);
PAINT GREEN (-5763 5558);
FORCEPROP 2 LAST CDS_LIB mstr_standard
J 2
(-5825 5550);
DISPLAY 0.723404 (-5825 5550);
PAINT MONO (-5825 5550);
DISPLAY INVISIBLE (-5825 5550);
FORCEPROP 1 LAST BODY_TYPE PLUMBING
J 2
(-5825 5600);
DISPLAY 0.872340 (-5825 5600);
PAINT GREEN (-5825 5600);
DISPLAY INVISIBLE (-5825 5600);
FORCEPROP 1 LAST HDL_TAP TRUE
J 2
(-6150 5425);
DISPLAY 0.872340 (-6150 5425);
DISPLAY INVISIBLE (-6150 5425);
FORCEPROP 1 LAST PATH I253
J 2
(-5823 5550);
DISPLAY 0.872340 (-5823 5550);
PAINT GREEN (-5823 5550);
DISPLAY INVISIBLE (-5823 5550);
FORCEADD TAP..1
R 2
(-5825 5450);
FORCEPROP 3 LASTPIN (-5775 5450) SIG_NAME M_E_CPU0_SA_DQS_DP<6>
J 0
(-5765 5460);
DISPLAY 0.659574 (-5765 5460);
PAINT MONO (-5765 5460);
DISPLAY INVISIBLE (-5765 5460);
FORCEPROP 1 LASTPIN (-5775 5450) BN 6
J 2
(-5763 5458);
DISPLAY 0.489362 (-5763 5458);
PAINT GREEN (-5763 5458);
FORCEPROP 2 LAST CDS_LIB mstr_standard
J 2
(-5825 5450);
DISPLAY 0.723404 (-5825 5450);
PAINT MONO (-5825 5450);
DISPLAY INVISIBLE (-5825 5450);
FORCEPROP 1 LAST BODY_TYPE PLUMBING
J 2
(-5825 5500);
DISPLAY 0.872340 (-5825 5500);
PAINT GREEN (-5825 5500);
DISPLAY INVISIBLE (-5825 5500);
FORCEPROP 1 LAST HDL_TAP TRUE
J 2
(-6150 5325);
DISPLAY 0.872340 (-6150 5325);
DISPLAY INVISIBLE (-6150 5325);
FORCEPROP 1 LAST PATH I254
J 2
(-5823 5450);
DISPLAY 0.872340 (-5823 5450);
PAINT GREEN (-5823 5450);
DISPLAY INVISIBLE (-5823 5450);
FORCEADD TAP..1
R 2
(-5825 5250);
FORCEPROP 3 LASTPIN (-5775 5250) SIG_NAME M_E_CPU0_SA_DQS_DP<8>
J 0
(-5765 5260);
DISPLAY 0.659574 (-5765 5260);
PAINT MONO (-5765 5260);
DISPLAY INVISIBLE (-5765 5260);
FORCEPROP 1 LASTPIN (-5775 5250) BN 8
J 2
(-5763 5258);
DISPLAY 0.489362 (-5763 5258);
PAINT GREEN (-5763 5258);
FORCEPROP 2 LAST CDS_LIB mstr_standard
J 2
(-5825 5250);
DISPLAY 0.723404 (-5825 5250);
PAINT MONO (-5825 5250);
DISPLAY INVISIBLE (-5825 5250);
FORCEPROP 1 LAST BODY_TYPE PLUMBING
J 2
(-5825 5300);
DISPLAY 0.872340 (-5825 5300);
PAINT GREEN (-5825 5300);
DISPLAY INVISIBLE (-5825 5300);
FORCEPROP 1 LAST HDL_TAP TRUE
J 2
(-6150 5125);
DISPLAY 0.872340 (-6150 5125);
DISPLAY INVISIBLE (-6150 5125);
FORCEPROP 1 LAST PATH I255
J 2
(-5823 5250);
DISPLAY 0.872340 (-5823 5250);
PAINT GREEN (-5823 5250);
DISPLAY INVISIBLE (-5823 5250);
FORCEADD TAP..1
R 2
(-5825 5350);
FORCEPROP 3 LASTPIN (-5775 5350) SIG_NAME M_E_CPU0_SA_DQS_DP<7>
J 0
(-5765 5360);
DISPLAY 0.659574 (-5765 5360);
PAINT MONO (-5765 5360);
DISPLAY INVISIBLE (-5765 5360);
FORCEPROP 1 LASTPIN (-5775 5350) BN 7
J 2
(-5763 5358);
DISPLAY 0.489362 (-5763 5358);
PAINT GREEN (-5763 5358);
FORCEPROP 2 LAST CDS_LIB mstr_standard
J 2
(-5825 5350);
DISPLAY 0.723404 (-5825 5350);
PAINT MONO (-5825 5350);
DISPLAY INVISIBLE (-5825 5350);
FORCEPROP 1 LAST BODY_TYPE PLUMBING
J 2
(-5825 5400);
DISPLAY 0.872340 (-5825 5400);
PAINT GREEN (-5825 5400);
DISPLAY INVISIBLE (-5825 5400);
FORCEPROP 1 LAST HDL_TAP TRUE
J 2
(-6150 5225);
DISPLAY 0.872340 (-6150 5225);
DISPLAY INVISIBLE (-6150 5225);
FORCEPROP 1 LAST PATH I256
J 2
(-5823 5350);
DISPLAY 0.872340 (-5823 5350);
PAINT GREEN (-5823 5350);
DISPLAY INVISIBLE (-5823 5350);
FORCEADD TAP..1
R 2
(-5825 5150);
FORCEPROP 3 LASTPIN (-5775 5150) SIG_NAME M_E_CPU0_SA_DQS_DP<9>
J 0
(-5765 5160);
DISPLAY 0.659574 (-5765 5160);
PAINT MONO (-5765 5160);
DISPLAY INVISIBLE (-5765 5160);
FORCEPROP 1 LASTPIN (-5775 5150) BN 9
J 2
(-5763 5158);
DISPLAY 0.489362 (-5763 5158);
PAINT GREEN (-5763 5158);
FORCEPROP 2 LAST CDS_LIB mstr_standard
J 2
(-5825 5150);
DISPLAY 0.723404 (-5825 5150);
PAINT MONO (-5825 5150);
DISPLAY INVISIBLE (-5825 5150);
FORCEPROP 1 LAST BODY_TYPE PLUMBING
J 2
(-5825 5200);
DISPLAY 0.872340 (-5825 5200);
PAINT GREEN (-5825 5200);
DISPLAY INVISIBLE (-5825 5200);
FORCEPROP 1 LAST HDL_TAP TRUE
J 2
(-6150 5025);
DISPLAY 0.872340 (-6150 5025);
DISPLAY INVISIBLE (-6150 5025);
FORCEPROP 1 LAST PATH I257
J 2
(-5823 5150);
DISPLAY 0.872340 (-5823 5150);
PAINT GREEN (-5823 5150);
DISPLAY INVISIBLE (-5823 5150);
FORCEADD TAP..1
R 2
(-6025 5600);
FORCEPROP 3 LASTPIN (-5975 5600) SIG_NAME M_E_CPU0_SA_DQS_DN<4>
J 0
(-5965 5610);
DISPLAY 0.659574 (-5965 5610);
PAINT MONO (-5965 5610);
DISPLAY INVISIBLE (-5965 5610);
FORCEPROP 1 LASTPIN (-5975 5600) BN 4
J 2
(-5963 5608);
DISPLAY 0.489362 (-5963 5608);
PAINT GREEN (-5963 5608);
FORCEPROP 2 LAST CDS_LIB mstr_standard
J 2
(-6025 5600);
DISPLAY 0.723404 (-6025 5600);
PAINT MONO (-6025 5600);
DISPLAY INVISIBLE (-6025 5600);
FORCEPROP 1 LAST BODY_TYPE PLUMBING
J 2
(-6025 5650);
DISPLAY 0.872340 (-6025 5650);
PAINT GREEN (-6025 5650);
DISPLAY INVISIBLE (-6025 5650);
FORCEPROP 1 LAST HDL_TAP TRUE
J 2
(-6350 5475);
DISPLAY 0.872340 (-6350 5475);
DISPLAY INVISIBLE (-6350 5475);
FORCEPROP 1 LAST PATH I258
J 2
(-6023 5600);
DISPLAY 0.872340 (-6023 5600);
PAINT GREEN (-6023 5600);
DISPLAY INVISIBLE (-6023 5600);
FORCEADD TAP..1
R 2
(-6025 5500);
FORCEPROP 3 LASTPIN (-5975 5500) SIG_NAME M_E_CPU0_SA_DQS_DN<5>
J 0
(-5965 5510);
DISPLAY 0.659574 (-5965 5510);
PAINT MONO (-5965 5510);
DISPLAY INVISIBLE (-5965 5510);
FORCEPROP 1 LASTPIN (-5975 5500) BN 5
J 2
(-5963 5508);
DISPLAY 0.489362 (-5963 5508);
PAINT GREEN (-5963 5508);
FORCEPROP 2 LAST CDS_LIB mstr_standard
J 2
(-6025 5500);
DISPLAY 0.723404 (-6025 5500);
PAINT MONO (-6025 5500);
DISPLAY INVISIBLE (-6025 5500);
FORCEPROP 1 LAST BODY_TYPE PLUMBING
J 2
(-6025 5550);
DISPLAY 0.872340 (-6025 5550);
PAINT GREEN (-6025 5550);
DISPLAY INVISIBLE (-6025 5550);
FORCEPROP 1 LAST HDL_TAP TRUE
J 2
(-6350 5375);
DISPLAY 0.872340 (-6350 5375);
DISPLAY INVISIBLE (-6350 5375);
FORCEPROP 1 LAST PATH I259
J 2
(-6023 5500);
DISPLAY 0.872340 (-6023 5500);
PAINT GREEN (-6023 5500);
DISPLAY INVISIBLE (-6023 5500);
FORCEADD TAP..1
R 2
(-6025 5400);
FORCEPROP 3 LASTPIN (-5975 5400) SIG_NAME M_E_CPU0_SA_DQS_DN<6>
J 0
(-5965 5410);
DISPLAY 0.659574 (-5965 5410);
PAINT MONO (-5965 5410);
DISPLAY INVISIBLE (-5965 5410);
FORCEPROP 1 LASTPIN (-5975 5400) BN 6
J 2
(-5963 5408);
DISPLAY 0.489362 (-5963 5408);
PAINT GREEN (-5963 5408);
FORCEPROP 2 LAST CDS_LIB mstr_standard
J 2
(-6025 5400);
DISPLAY 0.723404 (-6025 5400);
PAINT MONO (-6025 5400);
DISPLAY INVISIBLE (-6025 5400);
FORCEPROP 1 LAST BODY_TYPE PLUMBING
J 2
(-6025 5450);
DISPLAY 0.872340 (-6025 5450);
PAINT GREEN (-6025 5450);
DISPLAY INVISIBLE (-6025 5450);
FORCEPROP 1 LAST HDL_TAP TRUE
J 2
(-6350 5275);
DISPLAY 0.872340 (-6350 5275);
DISPLAY INVISIBLE (-6350 5275);
FORCEPROP 1 LAST PATH I260
J 2
(-6023 5400);
DISPLAY 0.872340 (-6023 5400);
PAINT GREEN (-6023 5400);
DISPLAY INVISIBLE (-6023 5400);
FORCEADD TAP..1
R 2
(-6025 5300);
FORCEPROP 3 LASTPIN (-5975 5300) SIG_NAME M_E_CPU0_SA_DQS_DN<7>
J 0
(-5965 5310);
DISPLAY 0.659574 (-5965 5310);
PAINT MONO (-5965 5310);
DISPLAY INVISIBLE (-5965 5310);
FORCEPROP 1 LASTPIN (-5975 5300) BN 7
J 2
(-5963 5308);
DISPLAY 0.489362 (-5963 5308);
PAINT GREEN (-5963 5308);
FORCEPROP 2 LAST CDS_LIB mstr_standard
J 2
(-6025 5300);
DISPLAY 0.723404 (-6025 5300);
PAINT MONO (-6025 5300);
DISPLAY INVISIBLE (-6025 5300);
FORCEPROP 1 LAST BODY_TYPE PLUMBING
J 2
(-6025 5350);
DISPLAY 0.872340 (-6025 5350);
PAINT GREEN (-6025 5350);
DISPLAY INVISIBLE (-6025 5350);
FORCEPROP 1 LAST HDL_TAP TRUE
J 2
(-6350 5175);
DISPLAY 0.872340 (-6350 5175);
DISPLAY INVISIBLE (-6350 5175);
FORCEPROP 1 LAST PATH I261
J 2
(-6023 5300);
DISPLAY 0.872340 (-6023 5300);
PAINT GREEN (-6023 5300);
DISPLAY INVISIBLE (-6023 5300);
FORCEADD TAP..1
R 2
(-6025 5200);
FORCEPROP 3 LASTPIN (-5975 5200) SIG_NAME M_E_CPU0_SA_DQS_DN<8>
J 0
(-5965 5210);
DISPLAY 0.659574 (-5965 5210);
PAINT MONO (-5965 5210);
DISPLAY INVISIBLE (-5965 5210);
FORCEPROP 1 LASTPIN (-5975 5200) BN 8
J 2
(-5963 5208);
DISPLAY 0.489362 (-5963 5208);
PAINT GREEN (-5963 5208);
FORCEPROP 2 LAST CDS_LIB mstr_standard
J 2
(-6025 5200);
DISPLAY 0.723404 (-6025 5200);
PAINT MONO (-6025 5200);
DISPLAY INVISIBLE (-6025 5200);
FORCEPROP 1 LAST BODY_TYPE PLUMBING
J 2
(-6025 5250);
DISPLAY 0.872340 (-6025 5250);
PAINT GREEN (-6025 5250);
DISPLAY INVISIBLE (-6025 5250);
FORCEPROP 1 LAST HDL_TAP TRUE
J 2
(-6350 5075);
DISPLAY 0.872340 (-6350 5075);
DISPLAY INVISIBLE (-6350 5075);
FORCEPROP 1 LAST PATH I262
J 2
(-6023 5200);
DISPLAY 0.872340 (-6023 5200);
PAINT GREEN (-6023 5200);
DISPLAY INVISIBLE (-6023 5200);
FORCEADD TAP..1
R 2
(-5825 4900);
FORCEPROP 3 LASTPIN (-5775 4900) SIG_NAME M_E_CPU0_SB_DQS_DP<1>
J 0
(-5765 4910);
DISPLAY 0.659574 (-5765 4910);
PAINT MONO (-5765 4910);
DISPLAY INVISIBLE (-5765 4910);
FORCEPROP 1 LASTPIN (-5775 4900) BN 1
J 2
(-5763 4908);
DISPLAY 0.489362 (-5763 4908);
PAINT GREEN (-5763 4908);
FORCEPROP 2 LAST CDS_LIB mstr_standard
J 2
(-5825 4900);
DISPLAY 0.723404 (-5825 4900);
PAINT MONO (-5825 4900);
DISPLAY INVISIBLE (-5825 4900);
FORCEPROP 1 LAST BODY_TYPE PLUMBING
J 2
(-5825 4950);
DISPLAY 0.872340 (-5825 4950);
PAINT GREEN (-5825 4950);
DISPLAY INVISIBLE (-5825 4950);
FORCEPROP 1 LAST HDL_TAP TRUE
J 2
(-6150 4775);
DISPLAY 0.872340 (-6150 4775);
DISPLAY INVISIBLE (-6150 4775);
FORCEPROP 1 LAST PATH I263
J 2
(-5823 4900);
DISPLAY 0.872340 (-5823 4900);
PAINT GREEN (-5823 4900);
DISPLAY INVISIBLE (-5823 4900);
FORCEADD TAP..1
R 2
(-5825 5000);
FORCEPROP 3 LASTPIN (-5775 5000) SIG_NAME M_E_CPU0_SB_DQS_DP<0>
J 0
(-5765 5010);
DISPLAY 0.659574 (-5765 5010);
PAINT MONO (-5765 5010);
DISPLAY INVISIBLE (-5765 5010);
FORCEPROP 1 LASTPIN (-5775 5000) BN 0
J 2
(-5763 5008);
DISPLAY 0.489362 (-5763 5008);
PAINT GREEN (-5763 5008);
FORCEPROP 2 LAST CDS_LIB mstr_standard
J 2
(-5825 5000);
DISPLAY 0.723404 (-5825 5000);
PAINT MONO (-5825 5000);
DISPLAY INVISIBLE (-5825 5000);
FORCEPROP 1 LAST BODY_TYPE PLUMBING
J 2
(-5825 5050);
DISPLAY 0.872340 (-5825 5050);
PAINT GREEN (-5825 5050);
DISPLAY INVISIBLE (-5825 5050);
FORCEPROP 1 LAST HDL_TAP TRUE
J 2
(-6150 4875);
DISPLAY 0.872340 (-6150 4875);
DISPLAY INVISIBLE (-6150 4875);
FORCEPROP 1 LAST PATH I264
J 2
(-5823 5000);
DISPLAY 0.872340 (-5823 5000);
PAINT GREEN (-5823 5000);
DISPLAY INVISIBLE (-5823 5000);
FORCEADD TAP..1
R 2
(-5825 4800);
FORCEPROP 3 LASTPIN (-5775 4800) SIG_NAME M_E_CPU0_SB_DQS_DP<2>
J 0
(-5765 4810);
DISPLAY 0.659574 (-5765 4810);
PAINT MONO (-5765 4810);
DISPLAY INVISIBLE (-5765 4810);
FORCEPROP 1 LASTPIN (-5775 4800) BN 2
J 2
(-5763 4808);
DISPLAY 0.489362 (-5763 4808);
PAINT GREEN (-5763 4808);
FORCEPROP 2 LAST CDS_LIB mstr_standard
J 2
(-5825 4800);
DISPLAY 0.723404 (-5825 4800);
PAINT MONO (-5825 4800);
DISPLAY INVISIBLE (-5825 4800);
FORCEPROP 1 LAST BODY_TYPE PLUMBING
J 2
(-5825 4850);
DISPLAY 0.872340 (-5825 4850);
PAINT GREEN (-5825 4850);
DISPLAY INVISIBLE (-5825 4850);
FORCEPROP 1 LAST HDL_TAP TRUE
J 2
(-6150 4675);
DISPLAY 0.872340 (-6150 4675);
DISPLAY INVISIBLE (-6150 4675);
FORCEPROP 1 LAST PATH I265
J 2
(-5823 4800);
DISPLAY 0.872340 (-5823 4800);
PAINT GREEN (-5823 4800);
DISPLAY INVISIBLE (-5823 4800);
FORCEADD TAP..1
R 2
(-5825 4700);
FORCEPROP 3 LASTPIN (-5775 4700) SIG_NAME M_E_CPU0_SB_DQS_DP<3>
J 0
(-5765 4710);
DISPLAY 0.659574 (-5765 4710);
PAINT MONO (-5765 4710);
DISPLAY INVISIBLE (-5765 4710);
FORCEPROP 1 LASTPIN (-5775 4700) BN 3
J 2
(-5763 4708);
DISPLAY 0.489362 (-5763 4708);
PAINT GREEN (-5763 4708);
FORCEPROP 2 LAST CDS_LIB mstr_standard
J 2
(-5825 4700);
DISPLAY 0.723404 (-5825 4700);
PAINT MONO (-5825 4700);
DISPLAY INVISIBLE (-5825 4700);
FORCEPROP 1 LAST BODY_TYPE PLUMBING
J 2
(-5825 4750);
DISPLAY 0.872340 (-5825 4750);
PAINT GREEN (-5825 4750);
DISPLAY INVISIBLE (-5825 4750);
FORCEPROP 1 LAST HDL_TAP TRUE
J 2
(-6150 4575);
DISPLAY 0.872340 (-6150 4575);
DISPLAY INVISIBLE (-6150 4575);
FORCEPROP 1 LAST PATH I266
J 2
(-5823 4700);
DISPLAY 0.872340 (-5823 4700);
PAINT GREEN (-5823 4700);
DISPLAY INVISIBLE (-5823 4700);
FORCEADD TAP..1
R 2
(-6025 4950);
FORCEPROP 3 LASTPIN (-5975 4950) SIG_NAME M_E_CPU0_SB_DQS_DN<0>
J 0
(-5965 4960);
DISPLAY 0.659574 (-5965 4960);
PAINT MONO (-5965 4960);
DISPLAY INVISIBLE (-5965 4960);
FORCEPROP 1 LASTPIN (-5975 4950) BN 0
J 2
(-5963 4958);
DISPLAY 0.489362 (-5963 4958);
PAINT GREEN (-5963 4958);
FORCEPROP 2 LAST CDS_LIB mstr_standard
J 2
(-6025 4950);
DISPLAY 0.723404 (-6025 4950);
PAINT MONO (-6025 4950);
DISPLAY INVISIBLE (-6025 4950);
FORCEPROP 1 LAST BODY_TYPE PLUMBING
J 2
(-6025 5000);
DISPLAY 0.872340 (-6025 5000);
PAINT GREEN (-6025 5000);
DISPLAY INVISIBLE (-6025 5000);
FORCEPROP 1 LAST HDL_TAP TRUE
J 2
(-6350 4825);
DISPLAY 0.872340 (-6350 4825);
DISPLAY INVISIBLE (-6350 4825);
FORCEPROP 1 LAST PATH I267
J 2
(-6023 4950);
DISPLAY 0.872340 (-6023 4950);
PAINT GREEN (-6023 4950);
DISPLAY INVISIBLE (-6023 4950);
FORCEADD TAP..1
R 2
(-6025 5100);
FORCEPROP 3 LASTPIN (-5975 5100) SIG_NAME M_E_CPU0_SA_DQS_DN<9>
J 0
(-5965 5110);
DISPLAY 0.659574 (-5965 5110);
PAINT MONO (-5965 5110);
DISPLAY INVISIBLE (-5965 5110);
FORCEPROP 1 LASTPIN (-5975 5100) BN 9
J 2
(-5963 5108);
DISPLAY 0.489362 (-5963 5108);
PAINT GREEN (-5963 5108);
FORCEPROP 2 LAST CDS_LIB mstr_standard
J 2
(-6025 5100);
DISPLAY 0.723404 (-6025 5100);
PAINT MONO (-6025 5100);
DISPLAY INVISIBLE (-6025 5100);
FORCEPROP 1 LAST BODY_TYPE PLUMBING
J 2
(-6025 5150);
DISPLAY 0.872340 (-6025 5150);
PAINT GREEN (-6025 5150);
DISPLAY INVISIBLE (-6025 5150);
FORCEPROP 1 LAST HDL_TAP TRUE
J 2
(-6350 4975);
DISPLAY 0.872340 (-6350 4975);
DISPLAY INVISIBLE (-6350 4975);
FORCEPROP 1 LAST PATH I268
J 2
(-6023 5100);
DISPLAY 0.872340 (-6023 5100);
PAINT GREEN (-6023 5100);
DISPLAY INVISIBLE (-6023 5100);
FORCEADD TAP..1
R 2
(-6025 4850);
FORCEPROP 3 LASTPIN (-5975 4850) SIG_NAME M_E_CPU0_SB_DQS_DN<1>
J 0
(-5965 4860);
DISPLAY 0.659574 (-5965 4860);
PAINT MONO (-5965 4860);
DISPLAY INVISIBLE (-5965 4860);
FORCEPROP 1 LASTPIN (-5975 4850) BN 1
J 2
(-5963 4858);
DISPLAY 0.489362 (-5963 4858);
PAINT GREEN (-5963 4858);
FORCEPROP 2 LAST CDS_LIB mstr_standard
J 2
(-6025 4850);
DISPLAY 0.723404 (-6025 4850);
PAINT MONO (-6025 4850);
DISPLAY INVISIBLE (-6025 4850);
FORCEPROP 1 LAST BODY_TYPE PLUMBING
J 2
(-6025 4900);
DISPLAY 0.872340 (-6025 4900);
PAINT GREEN (-6025 4900);
DISPLAY INVISIBLE (-6025 4900);
FORCEPROP 1 LAST HDL_TAP TRUE
J 2
(-6350 4725);
DISPLAY 0.872340 (-6350 4725);
DISPLAY INVISIBLE (-6350 4725);
FORCEPROP 1 LAST PATH I269
J 2
(-6023 4850);
DISPLAY 0.872340 (-6023 4850);
PAINT GREEN (-6023 4850);
DISPLAY INVISIBLE (-6023 4850);
FORCEADD TAP..1
R 2
(-6025 4750);
FORCEPROP 3 LASTPIN (-5975 4750) SIG_NAME M_E_CPU0_SB_DQS_DN<2>
J 0
(-5965 4760);
DISPLAY 0.659574 (-5965 4760);
PAINT MONO (-5965 4760);
DISPLAY INVISIBLE (-5965 4760);
FORCEPROP 1 LASTPIN (-5975 4750) BN 2
J 2
(-5963 4758);
DISPLAY 0.489362 (-5963 4758);
PAINT GREEN (-5963 4758);
FORCEPROP 2 LAST CDS_LIB mstr_standard
J 2
(-6025 4750);
DISPLAY 0.723404 (-6025 4750);
PAINT MONO (-6025 4750);
DISPLAY INVISIBLE (-6025 4750);
FORCEPROP 1 LAST BODY_TYPE PLUMBING
J 2
(-6025 4800);
DISPLAY 0.872340 (-6025 4800);
PAINT GREEN (-6025 4800);
DISPLAY INVISIBLE (-6025 4800);
FORCEPROP 1 LAST HDL_TAP TRUE
J 2
(-6350 4625);
DISPLAY 0.872340 (-6350 4625);
DISPLAY INVISIBLE (-6350 4625);
FORCEPROP 1 LAST PATH I270
J 2
(-6023 4750);
DISPLAY 0.872340 (-6023 4750);
PAINT GREEN (-6023 4750);
DISPLAY INVISIBLE (-6023 4750);
FORCEADD TAP..1
R 2
(-6025 4650);
FORCEPROP 3 LASTPIN (-5975 4650) SIG_NAME M_E_CPU0_SB_DQS_DN<3>
J 0
(-5965 4660);
DISPLAY 0.659574 (-5965 4660);
PAINT MONO (-5965 4660);
DISPLAY INVISIBLE (-5965 4660);
FORCEPROP 1 LASTPIN (-5975 4650) BN 3
J 2
(-5963 4658);
DISPLAY 0.489362 (-5963 4658);
PAINT GREEN (-5963 4658);
FORCEPROP 2 LAST CDS_LIB mstr_standard
J 2
(-6025 4650);
DISPLAY 0.723404 (-6025 4650);
PAINT MONO (-6025 4650);
DISPLAY INVISIBLE (-6025 4650);
FORCEPROP 1 LAST BODY_TYPE PLUMBING
J 2
(-6025 4700);
DISPLAY 0.872340 (-6025 4700);
PAINT GREEN (-6025 4700);
DISPLAY INVISIBLE (-6025 4700);
FORCEPROP 1 LAST HDL_TAP TRUE
J 2
(-6350 4525);
DISPLAY 0.872340 (-6350 4525);
DISPLAY INVISIBLE (-6350 4525);
FORCEPROP 1 LAST PATH I271
J 2
(-6023 4650);
DISPLAY 0.872340 (-6023 4650);
PAINT GREEN (-6023 4650);
DISPLAY INVISIBLE (-6023 4650);
FORCEADD TAP..1
R 2
(-5825 4600);
FORCEPROP 3 LASTPIN (-5775 4600) SIG_NAME M_E_CPU0_SB_DQS_DP<4>
J 0
(-5765 4610);
DISPLAY 0.659574 (-5765 4610);
PAINT MONO (-5765 4610);
DISPLAY INVISIBLE (-5765 4610);
FORCEPROP 1 LASTPIN (-5775 4600) BN 4
J 2
(-5763 4608);
DISPLAY 0.489362 (-5763 4608);
PAINT GREEN (-5763 4608);
FORCEPROP 2 LAST CDS_LIB mstr_standard
J 2
(-5825 4600);
DISPLAY 0.723404 (-5825 4600);
PAINT MONO (-5825 4600);
DISPLAY INVISIBLE (-5825 4600);
FORCEPROP 1 LAST BODY_TYPE PLUMBING
J 2
(-5825 4650);
DISPLAY 0.872340 (-5825 4650);
PAINT GREEN (-5825 4650);
DISPLAY INVISIBLE (-5825 4650);
FORCEPROP 1 LAST HDL_TAP TRUE
J 2
(-6150 4475);
DISPLAY 0.872340 (-6150 4475);
DISPLAY INVISIBLE (-6150 4475);
FORCEPROP 1 LAST PATH I272
J 2
(-5823 4600);
DISPLAY 0.872340 (-5823 4600);
PAINT GREEN (-5823 4600);
DISPLAY INVISIBLE (-5823 4600);
FORCEADD TAP..1
R 2
(-5825 4500);
FORCEPROP 3 LASTPIN (-5775 4500) SIG_NAME M_E_CPU0_SB_DQS_DP<5>
J 0
(-5765 4510);
DISPLAY 0.659574 (-5765 4510);
PAINT MONO (-5765 4510);
DISPLAY INVISIBLE (-5765 4510);
FORCEPROP 1 LASTPIN (-5775 4500) BN 5
J 2
(-5763 4508);
DISPLAY 0.489362 (-5763 4508);
PAINT GREEN (-5763 4508);
FORCEPROP 2 LAST CDS_LIB mstr_standard
J 2
(-5825 4500);
DISPLAY 0.723404 (-5825 4500);
PAINT MONO (-5825 4500);
DISPLAY INVISIBLE (-5825 4500);
FORCEPROP 1 LAST BODY_TYPE PLUMBING
J 2
(-5825 4550);
DISPLAY 0.872340 (-5825 4550);
PAINT GREEN (-5825 4550);
DISPLAY INVISIBLE (-5825 4550);
FORCEPROP 1 LAST HDL_TAP TRUE
J 2
(-6150 4375);
DISPLAY 0.872340 (-6150 4375);
DISPLAY INVISIBLE (-6150 4375);
FORCEPROP 1 LAST PATH I273
J 2
(-5823 4500);
DISPLAY 0.872340 (-5823 4500);
PAINT GREEN (-5823 4500);
DISPLAY INVISIBLE (-5823 4500);
FORCEADD TAP..1
R 2
(-5825 4400);
FORCEPROP 3 LASTPIN (-5775 4400) SIG_NAME M_E_CPU0_SB_DQS_DP<6>
J 0
(-5765 4410);
DISPLAY 0.659574 (-5765 4410);
PAINT MONO (-5765 4410);
DISPLAY INVISIBLE (-5765 4410);
FORCEPROP 1 LASTPIN (-5775 4400) BN 6
J 2
(-5763 4408);
DISPLAY 0.489362 (-5763 4408);
PAINT GREEN (-5763 4408);
FORCEPROP 2 LAST CDS_LIB mstr_standard
J 2
(-5825 4400);
DISPLAY 0.723404 (-5825 4400);
PAINT MONO (-5825 4400);
DISPLAY INVISIBLE (-5825 4400);
FORCEPROP 1 LAST BODY_TYPE PLUMBING
J 2
(-5825 4450);
DISPLAY 0.872340 (-5825 4450);
PAINT GREEN (-5825 4450);
DISPLAY INVISIBLE (-5825 4450);
FORCEPROP 1 LAST HDL_TAP TRUE
J 2
(-6150 4275);
DISPLAY 0.872340 (-6150 4275);
DISPLAY INVISIBLE (-6150 4275);
FORCEPROP 1 LAST PATH I274
J 2
(-5823 4400);
DISPLAY 0.872340 (-5823 4400);
PAINT GREEN (-5823 4400);
DISPLAY INVISIBLE (-5823 4400);
FORCEADD TAP..1
R 2
(-5825 4200);
FORCEPROP 3 LASTPIN (-5775 4200) SIG_NAME M_E_CPU0_SB_DQS_DP<8>
J 0
(-5765 4210);
DISPLAY 0.659574 (-5765 4210);
PAINT MONO (-5765 4210);
DISPLAY INVISIBLE (-5765 4210);
FORCEPROP 1 LASTPIN (-5775 4200) BN 8
J 2
(-5763 4208);
DISPLAY 0.489362 (-5763 4208);
PAINT GREEN (-5763 4208);
FORCEPROP 2 LAST CDS_LIB mstr_standard
J 2
(-5825 4200);
DISPLAY 0.723404 (-5825 4200);
PAINT MONO (-5825 4200);
DISPLAY INVISIBLE (-5825 4200);
FORCEPROP 1 LAST BODY_TYPE PLUMBING
J 2
(-5825 4250);
DISPLAY 0.872340 (-5825 4250);
PAINT GREEN (-5825 4250);
DISPLAY INVISIBLE (-5825 4250);
FORCEPROP 1 LAST HDL_TAP TRUE
J 2
(-6150 4075);
DISPLAY 0.872340 (-6150 4075);
DISPLAY INVISIBLE (-6150 4075);
FORCEPROP 1 LAST PATH I275
J 2
(-5823 4200);
DISPLAY 0.872340 (-5823 4200);
PAINT GREEN (-5823 4200);
DISPLAY INVISIBLE (-5823 4200);
FORCEADD TAP..1
R 2
(-5825 4300);
FORCEPROP 3 LASTPIN (-5775 4300) SIG_NAME M_E_CPU0_SB_DQS_DP<7>
J 0
(-5765 4310);
DISPLAY 0.659574 (-5765 4310);
PAINT MONO (-5765 4310);
DISPLAY INVISIBLE (-5765 4310);
FORCEPROP 1 LASTPIN (-5775 4300) BN 7
J 2
(-5763 4308);
DISPLAY 0.489362 (-5763 4308);
PAINT GREEN (-5763 4308);
FORCEPROP 2 LAST CDS_LIB mstr_standard
J 2
(-5825 4300);
DISPLAY 0.723404 (-5825 4300);
PAINT MONO (-5825 4300);
DISPLAY INVISIBLE (-5825 4300);
FORCEPROP 1 LAST BODY_TYPE PLUMBING
J 2
(-5825 4350);
DISPLAY 0.872340 (-5825 4350);
PAINT GREEN (-5825 4350);
DISPLAY INVISIBLE (-5825 4350);
FORCEPROP 1 LAST HDL_TAP TRUE
J 2
(-6150 4175);
DISPLAY 0.872340 (-6150 4175);
DISPLAY INVISIBLE (-6150 4175);
FORCEPROP 1 LAST PATH I276
J 2
(-5823 4300);
DISPLAY 0.872340 (-5823 4300);
PAINT GREEN (-5823 4300);
DISPLAY INVISIBLE (-5823 4300);
FORCEADD TAP..1
R 2
(-5825 4100);
FORCEPROP 3 LASTPIN (-5775 4100) SIG_NAME M_E_CPU0_SB_DQS_DP<9>
J 0
(-5765 4110);
DISPLAY 0.659574 (-5765 4110);
PAINT MONO (-5765 4110);
DISPLAY INVISIBLE (-5765 4110);
FORCEPROP 1 LASTPIN (-5775 4100) BN 9
J 2
(-5763 4108);
DISPLAY 0.489362 (-5763 4108);
PAINT GREEN (-5763 4108);
FORCEPROP 2 LAST CDS_LIB mstr_standard
J 2
(-5825 4100);
DISPLAY 0.723404 (-5825 4100);
PAINT MONO (-5825 4100);
DISPLAY INVISIBLE (-5825 4100);
FORCEPROP 1 LAST BODY_TYPE PLUMBING
J 2
(-5825 4150);
DISPLAY 0.872340 (-5825 4150);
PAINT GREEN (-5825 4150);
DISPLAY INVISIBLE (-5825 4150);
FORCEPROP 1 LAST HDL_TAP TRUE
J 2
(-6150 3975);
DISPLAY 0.872340 (-6150 3975);
DISPLAY INVISIBLE (-6150 3975);
FORCEPROP 1 LAST PATH I277
J 2
(-5823 4100);
DISPLAY 0.872340 (-5823 4100);
PAINT GREEN (-5823 4100);
DISPLAY INVISIBLE (-5823 4100);
FORCEADD TAP..1
R 2
(-6025 4550);
FORCEPROP 3 LASTPIN (-5975 4550) SIG_NAME M_E_CPU0_SB_DQS_DN<4>
J 0
(-5965 4560);
DISPLAY 0.659574 (-5965 4560);
PAINT MONO (-5965 4560);
DISPLAY INVISIBLE (-5965 4560);
FORCEPROP 1 LASTPIN (-5975 4550) BN 4
J 2
(-5963 4558);
DISPLAY 0.489362 (-5963 4558);
PAINT GREEN (-5963 4558);
FORCEPROP 2 LAST CDS_LIB mstr_standard
J 2
(-6025 4550);
DISPLAY 0.723404 (-6025 4550);
PAINT MONO (-6025 4550);
DISPLAY INVISIBLE (-6025 4550);
FORCEPROP 1 LAST BODY_TYPE PLUMBING
J 2
(-6025 4600);
DISPLAY 0.872340 (-6025 4600);
PAINT GREEN (-6025 4600);
DISPLAY INVISIBLE (-6025 4600);
FORCEPROP 1 LAST HDL_TAP TRUE
J 2
(-6350 4425);
DISPLAY 0.872340 (-6350 4425);
DISPLAY INVISIBLE (-6350 4425);
FORCEPROP 1 LAST PATH I278
J 2
(-6023 4550);
DISPLAY 0.872340 (-6023 4550);
PAINT GREEN (-6023 4550);
DISPLAY INVISIBLE (-6023 4550);
FORCEADD TAP..1
R 2
(-6025 4450);
FORCEPROP 3 LASTPIN (-5975 4450) SIG_NAME M_E_CPU0_SB_DQS_DN<5>
J 0
(-5965 4460);
DISPLAY 0.659574 (-5965 4460);
PAINT MONO (-5965 4460);
DISPLAY INVISIBLE (-5965 4460);
FORCEPROP 1 LASTPIN (-5975 4450) BN 5
J 2
(-5963 4458);
DISPLAY 0.489362 (-5963 4458);
PAINT GREEN (-5963 4458);
FORCEPROP 2 LAST CDS_LIB mstr_standard
J 2
(-6025 4450);
DISPLAY 0.723404 (-6025 4450);
PAINT MONO (-6025 4450);
DISPLAY INVISIBLE (-6025 4450);
FORCEPROP 1 LAST BODY_TYPE PLUMBING
J 2
(-6025 4500);
DISPLAY 0.872340 (-6025 4500);
PAINT GREEN (-6025 4500);
DISPLAY INVISIBLE (-6025 4500);
FORCEPROP 1 LAST HDL_TAP TRUE
J 2
(-6350 4325);
DISPLAY 0.872340 (-6350 4325);
DISPLAY INVISIBLE (-6350 4325);
FORCEPROP 1 LAST PATH I279
J 2
(-6023 4450);
DISPLAY 0.872340 (-6023 4450);
PAINT GREEN (-6023 4450);
DISPLAY INVISIBLE (-6023 4450);
FORCEADD TAP..1
R 2
(-6025 4350);
FORCEPROP 3 LASTPIN (-5975 4350) SIG_NAME M_E_CPU0_SB_DQS_DN<6>
J 0
(-5965 4360);
DISPLAY 0.659574 (-5965 4360);
PAINT MONO (-5965 4360);
DISPLAY INVISIBLE (-5965 4360);
FORCEPROP 1 LASTPIN (-5975 4350) BN 6
J 2
(-5963 4358);
DISPLAY 0.489362 (-5963 4358);
PAINT GREEN (-5963 4358);
FORCEPROP 2 LAST CDS_LIB mstr_standard
J 2
(-6025 4350);
DISPLAY 0.723404 (-6025 4350);
PAINT MONO (-6025 4350);
DISPLAY INVISIBLE (-6025 4350);
FORCEPROP 1 LAST BODY_TYPE PLUMBING
J 2
(-6025 4400);
DISPLAY 0.872340 (-6025 4400);
PAINT GREEN (-6025 4400);
DISPLAY INVISIBLE (-6025 4400);
FORCEPROP 1 LAST HDL_TAP TRUE
J 2
(-6350 4225);
DISPLAY 0.872340 (-6350 4225);
DISPLAY INVISIBLE (-6350 4225);
FORCEPROP 1 LAST PATH I280
J 2
(-6023 4350);
DISPLAY 0.872340 (-6023 4350);
PAINT GREEN (-6023 4350);
DISPLAY INVISIBLE (-6023 4350);
FORCEADD TAP..1
R 2
(-6025 4250);
FORCEPROP 3 LASTPIN (-5975 4250) SIG_NAME M_E_CPU0_SB_DQS_DN<7>
J 0
(-5965 4260);
DISPLAY 0.659574 (-5965 4260);
PAINT MONO (-5965 4260);
DISPLAY INVISIBLE (-5965 4260);
FORCEPROP 1 LASTPIN (-5975 4250) BN 7
J 2
(-5963 4258);
DISPLAY 0.489362 (-5963 4258);
PAINT GREEN (-5963 4258);
FORCEPROP 2 LAST CDS_LIB mstr_standard
J 2
(-6025 4250);
DISPLAY 0.723404 (-6025 4250);
PAINT MONO (-6025 4250);
DISPLAY INVISIBLE (-6025 4250);
FORCEPROP 1 LAST BODY_TYPE PLUMBING
J 2
(-6025 4300);
DISPLAY 0.872340 (-6025 4300);
PAINT GREEN (-6025 4300);
DISPLAY INVISIBLE (-6025 4300);
FORCEPROP 1 LAST HDL_TAP TRUE
J 2
(-6350 4125);
DISPLAY 0.872340 (-6350 4125);
DISPLAY INVISIBLE (-6350 4125);
FORCEPROP 1 LAST PATH I281
J 2
(-6023 4250);
DISPLAY 0.872340 (-6023 4250);
PAINT GREEN (-6023 4250);
DISPLAY INVISIBLE (-6023 4250);
FORCEADD TAP..1
R 2
(-6025 4150);
FORCEPROP 3 LASTPIN (-5975 4150) SIG_NAME M_E_CPU0_SB_DQS_DN<8>
J 0
(-5965 4160);
DISPLAY 0.659574 (-5965 4160);
PAINT MONO (-5965 4160);
DISPLAY INVISIBLE (-5965 4160);
FORCEPROP 1 LASTPIN (-5975 4150) BN 8
J 2
(-5963 4158);
DISPLAY 0.489362 (-5963 4158);
PAINT GREEN (-5963 4158);
FORCEPROP 2 LAST CDS_LIB mstr_standard
J 2
(-6025 4150);
DISPLAY 0.723404 (-6025 4150);
PAINT MONO (-6025 4150);
DISPLAY INVISIBLE (-6025 4150);
FORCEPROP 1 LAST BODY_TYPE PLUMBING
J 2
(-6025 4200);
DISPLAY 0.872340 (-6025 4200);
PAINT GREEN (-6025 4200);
DISPLAY INVISIBLE (-6025 4200);
FORCEPROP 1 LAST HDL_TAP TRUE
J 2
(-6350 4025);
DISPLAY 0.872340 (-6350 4025);
DISPLAY INVISIBLE (-6350 4025);
FORCEPROP 1 LAST PATH I282
J 2
(-6023 4150);
DISPLAY 0.872340 (-6023 4150);
PAINT GREEN (-6023 4150);
DISPLAY INVISIBLE (-6023 4150);
FORCEADD OFFPAGE..3
R 2
(-6725 6075);
FORCEPROP 2 LAST $XR0 90 
J 0
(-6974 6075);
DISPLAY 0.638298 (-6974 6075);
PAINT MONO (-6974 6075);
FORCEPROP 2 LAST CDS_LIB standard
J 0
(-6725 6075);
DISPLAY INVISIBLE (-6725 6075);
FORCEPROP 1 LAST OFFPAGE TRUE
J 2
(-7050 5950);
DISPLAY 0.872340 (-7050 5950);
PAINT GREEN (-7050 5950);
DISPLAY INVISIBLE (-7050 5950);
FORCEPROP 1 LAST COMMENT_BODY TRUE
J 2
(-6675 5975);
DISPLAY 0.872340 (-6675 5975);
PAINT GREEN (-6675 5975);
DISPLAY INVISIBLE (-6675 5975);
FORCEPROP 2 LAST PATH I283
J 0
(-7000 6125);
DISPLAY 1.021277 (-7000 6125);
DISPLAY INVISIBLE (-7000 6125);
FORCEADD OFFPAGE..3
R 2
(-6725 6025);
FORCEPROP 2 LAST $XR0 90 
J 0
(-6974 6025);
DISPLAY 0.638298 (-6974 6025);
PAINT MONO (-6974 6025);
FORCEPROP 2 LAST CDS_LIB standard
J 0
(-6725 6025);
DISPLAY INVISIBLE (-6725 6025);
FORCEPROP 1 LAST OFFPAGE TRUE
J 2
(-7050 5900);
DISPLAY 0.872340 (-7050 5900);
PAINT GREEN (-7050 5900);
DISPLAY INVISIBLE (-7050 5900);
FORCEPROP 1 LAST COMMENT_BODY TRUE
J 2
(-6675 5925);
DISPLAY 0.872340 (-6675 5925);
PAINT GREEN (-6675 5925);
DISPLAY INVISIBLE (-6675 5925);
FORCEPROP 2 LAST PATH I284
J 0
(-7000 6075);
DISPLAY 1.021277 (-7000 6075);
DISPLAY INVISIBLE (-7000 6075);
FORCEADD OFFPAGE..3
R 2
(-6725 5025);
FORCEPROP 2 LAST $XR0 90 
J 0
(-6974 5025);
DISPLAY 0.638298 (-6974 5025);
PAINT MONO (-6974 5025);
FORCEPROP 2 LAST CDS_LIB standard
J 0
(-6725 5025);
DISPLAY INVISIBLE (-6725 5025);
FORCEPROP 1 LAST OFFPAGE TRUE
J 2
(-7050 4900);
DISPLAY 0.872340 (-7050 4900);
PAINT GREEN (-7050 4900);
DISPLAY INVISIBLE (-7050 4900);
FORCEPROP 1 LAST COMMENT_BODY TRUE
J 2
(-6675 4925);
DISPLAY 0.872340 (-6675 4925);
PAINT GREEN (-6675 4925);
DISPLAY INVISIBLE (-6675 4925);
FORCEPROP 2 LAST PATH I285
J 0
(-7000 5075);
DISPLAY 1.021277 (-7000 5075);
DISPLAY INVISIBLE (-7000 5075);
FORCEADD OFFPAGE..3
R 2
(-6725 4975);
FORCEPROP 2 LAST $XR0 90 
J 0
(-6974 4975);
DISPLAY 0.638298 (-6974 4975);
PAINT MONO (-6974 4975);
FORCEPROP 2 LAST CDS_LIB standard
J 0
(-6725 4975);
DISPLAY INVISIBLE (-6725 4975);
FORCEPROP 1 LAST OFFPAGE TRUE
J 2
(-7050 4850);
DISPLAY 0.872340 (-7050 4850);
PAINT GREEN (-7050 4850);
DISPLAY INVISIBLE (-7050 4850);
FORCEPROP 1 LAST COMMENT_BODY TRUE
J 2
(-6675 4875);
DISPLAY 0.872340 (-6675 4875);
PAINT GREEN (-6675 4875);
DISPLAY INVISIBLE (-6675 4875);
FORCEPROP 2 LAST PATH I286
J 0
(-7000 5025);
DISPLAY 1.021277 (-7000 5025);
DISPLAY INVISIBLE (-7000 5025);
FORCEADD TAP..1
R 2
(-6025 4050);
FORCEPROP 3 LASTPIN (-5975 4050) SIG_NAME M_E_CPU0_SB_DQS_DN<9>
J 0
(-5965 4060);
DISPLAY 0.659574 (-5965 4060);
PAINT MONO (-5965 4060);
DISPLAY INVISIBLE (-5965 4060);
FORCEPROP 1 LASTPIN (-5975 4050) BN 9
J 2
(-5963 4058);
DISPLAY 0.489362 (-5963 4058);
PAINT GREEN (-5963 4058);
FORCEPROP 2 LAST CDS_LIB mstr_standard
J 2
(-6025 4050);
DISPLAY 0.723404 (-6025 4050);
PAINT MONO (-6025 4050);
DISPLAY INVISIBLE (-6025 4050);
FORCEPROP 1 LAST BODY_TYPE PLUMBING
J 2
(-6025 4100);
DISPLAY 0.872340 (-6025 4100);
PAINT GREEN (-6025 4100);
DISPLAY INVISIBLE (-6025 4100);
FORCEPROP 1 LAST HDL_TAP TRUE
J 2
(-6350 3925);
DISPLAY 0.872340 (-6350 3925);
DISPLAY INVISIBLE (-6350 3925);
FORCEPROP 1 LAST PATH I287
J 2
(-6023 4050);
DISPLAY 0.872340 (-6023 4050);
PAINT GREEN (-6023 4050);
DISPLAY INVISIBLE (-6023 4050);
FORCEADD TAP..1
R 2
(-6025 3900);
FORCEPROP 3 LASTPIN (-5975 3900) SIG_NAME M_E_CPU0_SA_CA<0>
J 0
(-5965 3910);
DISPLAY 0.659574 (-5965 3910);
PAINT MONO (-5965 3910);
DISPLAY INVISIBLE (-5965 3910);
FORCEPROP 1 LASTPIN (-5975 3900) BN 0
J 2
(-5963 3908);
DISPLAY 0.489362 (-5963 3908);
PAINT GREEN (-5963 3908);
FORCEPROP 2 LAST CDS_LIB mstr_standard
J 0
(-6025 3900);
DISPLAY 0.723404 (-6025 3900);
PAINT MONO (-6025 3900);
DISPLAY INVISIBLE (-6025 3900);
FORCEPROP 1 LAST BODY_TYPE PLUMBING
J 2
(-6025 3950);
DISPLAY 0.872340 (-6025 3950);
PAINT GREEN (-6025 3950);
DISPLAY INVISIBLE (-6025 3950);
FORCEPROP 1 LAST HDL_TAP TRUE
J 2
(-6350 3775);
DISPLAY 0.872340 (-6350 3775);
DISPLAY INVISIBLE (-6350 3775);
FORCEPROP 1 LAST PATH I288
J 2
(-6023 3900);
DISPLAY 0.872340 (-6023 3900);
PAINT GREEN (-6023 3900);
DISPLAY INVISIBLE (-6023 3900);
FORCEADD TAP..1
R 2
(-6025 3850);
FORCEPROP 3 LASTPIN (-5975 3850) SIG_NAME M_E_CPU0_SA_CA<1>
J 0
(-5965 3860);
DISPLAY 0.659574 (-5965 3860);
PAINT MONO (-5965 3860);
DISPLAY INVISIBLE (-5965 3860);
FORCEPROP 1 LASTPIN (-5975 3850) BN 1
J 2
(-5963 3858);
DISPLAY 0.489362 (-5963 3858);
PAINT GREEN (-5963 3858);
FORCEPROP 2 LAST CDS_LIB mstr_standard
J 0
(-6025 3850);
DISPLAY 0.723404 (-6025 3850);
PAINT MONO (-6025 3850);
DISPLAY INVISIBLE (-6025 3850);
FORCEPROP 1 LAST BODY_TYPE PLUMBING
J 2
(-6025 3900);
DISPLAY 0.872340 (-6025 3900);
PAINT GREEN (-6025 3900);
DISPLAY INVISIBLE (-6025 3900);
FORCEPROP 1 LAST HDL_TAP TRUE
J 2
(-6350 3725);
DISPLAY 0.872340 (-6350 3725);
DISPLAY INVISIBLE (-6350 3725);
FORCEPROP 1 LAST PATH I289
J 2
(-6023 3850);
DISPLAY 0.872340 (-6023 3850);
PAINT GREEN (-6023 3850);
DISPLAY INVISIBLE (-6023 3850);
FORCEADD TAP..1
R 2
(-6025 3800);
FORCEPROP 3 LASTPIN (-5975 3800) SIG_NAME M_E_CPU0_SA_CA<2>
J 0
(-5965 3810);
DISPLAY 0.659574 (-5965 3810);
PAINT MONO (-5965 3810);
DISPLAY INVISIBLE (-5965 3810);
FORCEPROP 1 LASTPIN (-5975 3800) BN 2
J 2
(-5963 3808);
DISPLAY 0.489362 (-5963 3808);
PAINT GREEN (-5963 3808);
FORCEPROP 2 LAST CDS_LIB mstr_standard
J 0
(-6025 3800);
DISPLAY 0.723404 (-6025 3800);
PAINT MONO (-6025 3800);
DISPLAY INVISIBLE (-6025 3800);
FORCEPROP 1 LAST BODY_TYPE PLUMBING
J 2
(-6025 3850);
DISPLAY 0.872340 (-6025 3850);
PAINT GREEN (-6025 3850);
DISPLAY INVISIBLE (-6025 3850);
FORCEPROP 1 LAST HDL_TAP TRUE
J 2
(-6350 3675);
DISPLAY 0.872340 (-6350 3675);
DISPLAY INVISIBLE (-6350 3675);
FORCEPROP 1 LAST PATH I290
J 2
(-6023 3800);
DISPLAY 0.872340 (-6023 3800);
PAINT GREEN (-6023 3800);
DISPLAY INVISIBLE (-6023 3800);
FORCEADD TAP..1
R 2
(-6025 3750);
FORCEPROP 3 LASTPIN (-5975 3750) SIG_NAME M_E_CPU0_SA_CA<3>
J 0
(-5965 3760);
DISPLAY 0.659574 (-5965 3760);
PAINT MONO (-5965 3760);
DISPLAY INVISIBLE (-5965 3760);
FORCEPROP 1 LASTPIN (-5975 3750) BN 3
J 2
(-5963 3758);
DISPLAY 0.489362 (-5963 3758);
PAINT GREEN (-5963 3758);
FORCEPROP 2 LAST CDS_LIB mstr_standard
J 0
(-6025 3750);
DISPLAY 0.723404 (-6025 3750);
PAINT MONO (-6025 3750);
DISPLAY INVISIBLE (-6025 3750);
FORCEPROP 1 LAST BODY_TYPE PLUMBING
J 2
(-6025 3800);
DISPLAY 0.872340 (-6025 3800);
PAINT GREEN (-6025 3800);
DISPLAY INVISIBLE (-6025 3800);
FORCEPROP 1 LAST HDL_TAP TRUE
J 2
(-6350 3625);
DISPLAY 0.872340 (-6350 3625);
DISPLAY INVISIBLE (-6350 3625);
FORCEPROP 1 LAST PATH I291
J 2
(-6023 3750);
DISPLAY 0.872340 (-6023 3750);
PAINT GREEN (-6023 3750);
DISPLAY INVISIBLE (-6023 3750);
FORCEADD TAP..1
R 2
(-6025 3600);
FORCEPROP 3 LASTPIN (-5975 3600) SIG_NAME M_E_CPU0_SA_CA<6>
J 0
(-5965 3610);
DISPLAY 0.659574 (-5965 3610);
PAINT MONO (-5965 3610);
DISPLAY INVISIBLE (-5965 3610);
FORCEPROP 1 LASTPIN (-5975 3600) BN 6
J 2
(-5963 3608);
DISPLAY 0.489362 (-5963 3608);
PAINT GREEN (-5963 3608);
FORCEPROP 2 LAST CDS_LIB mstr_standard
J 0
(-6025 3600);
DISPLAY 0.723404 (-6025 3600);
PAINT MONO (-6025 3600);
DISPLAY INVISIBLE (-6025 3600);
FORCEPROP 1 LAST BODY_TYPE PLUMBING
J 2
(-6025 3650);
DISPLAY 0.872340 (-6025 3650);
PAINT GREEN (-6025 3650);
DISPLAY INVISIBLE (-6025 3650);
FORCEPROP 1 LAST HDL_TAP TRUE
J 2
(-6350 3475);
DISPLAY 0.872340 (-6350 3475);
DISPLAY INVISIBLE (-6350 3475);
FORCEPROP 1 LAST PATH I292
J 2
(-6023 3600);
DISPLAY 0.872340 (-6023 3600);
PAINT GREEN (-6023 3600);
DISPLAY INVISIBLE (-6023 3600);
FORCEADD TAP..1
R 2
(-6025 3650);
FORCEPROP 3 LASTPIN (-5975 3650) SIG_NAME M_E_CPU0_SA_CA<5>
J 0
(-5965 3660);
DISPLAY 0.659574 (-5965 3660);
PAINT MONO (-5965 3660);
DISPLAY INVISIBLE (-5965 3660);
FORCEPROP 1 LASTPIN (-5975 3650) BN 5
J 2
(-5963 3658);
DISPLAY 0.489362 (-5963 3658);
PAINT GREEN (-5963 3658);
FORCEPROP 2 LAST CDS_LIB mstr_standard
J 0
(-6025 3650);
DISPLAY 0.723404 (-6025 3650);
PAINT MONO (-6025 3650);
DISPLAY INVISIBLE (-6025 3650);
FORCEPROP 1 LAST BODY_TYPE PLUMBING
J 2
(-6025 3700);
DISPLAY 0.872340 (-6025 3700);
PAINT GREEN (-6025 3700);
DISPLAY INVISIBLE (-6025 3700);
FORCEPROP 1 LAST HDL_TAP TRUE
J 2
(-6350 3525);
DISPLAY 0.872340 (-6350 3525);
DISPLAY INVISIBLE (-6350 3525);
FORCEPROP 1 LAST PATH I293
J 2
(-6023 3650);
DISPLAY 0.872340 (-6023 3650);
PAINT GREEN (-6023 3650);
DISPLAY INVISIBLE (-6023 3650);
FORCEADD TAP..1
R 2
(-6025 3700);
FORCEPROP 3 LASTPIN (-5975 3700) SIG_NAME M_E_CPU0_SA_CA<4>
J 0
(-5965 3710);
DISPLAY 0.659574 (-5965 3710);
PAINT MONO (-5965 3710);
DISPLAY INVISIBLE (-5965 3710);
FORCEPROP 1 LASTPIN (-5975 3700) BN 4
J 2
(-5963 3708);
DISPLAY 0.489362 (-5963 3708);
PAINT GREEN (-5963 3708);
FORCEPROP 2 LAST CDS_LIB mstr_standard
J 0
(-6025 3700);
DISPLAY 0.723404 (-6025 3700);
PAINT MONO (-6025 3700);
DISPLAY INVISIBLE (-6025 3700);
FORCEPROP 1 LAST BODY_TYPE PLUMBING
J 2
(-6025 3750);
DISPLAY 0.872340 (-6025 3750);
PAINT GREEN (-6025 3750);
DISPLAY INVISIBLE (-6025 3750);
FORCEPROP 1 LAST HDL_TAP TRUE
J 2
(-6350 3575);
DISPLAY 0.872340 (-6350 3575);
DISPLAY INVISIBLE (-6350 3575);
FORCEPROP 1 LAST PATH I294
J 2
(-6023 3700);
DISPLAY 0.872340 (-6023 3700);
PAINT GREEN (-6023 3700);
DISPLAY INVISIBLE (-6023 3700);
FORCEADD TAP..1
R 2
(-6025 3500);
FORCEPROP 3 LASTPIN (-5975 3500) SIG_NAME M_E_CPU0_SB_CA<0>
J 0
(-5965 3510);
DISPLAY 0.659574 (-5965 3510);
PAINT MONO (-5965 3510);
DISPLAY INVISIBLE (-5965 3510);
FORCEPROP 1 LASTPIN (-5975 3500) BN 0
J 2
(-5963 3508);
DISPLAY 0.489362 (-5963 3508);
PAINT GREEN (-5963 3508);
FORCEPROP 2 LAST CDS_LIB mstr_standard
J 0
(-6025 3500);
DISPLAY 0.723404 (-6025 3500);
PAINT MONO (-6025 3500);
DISPLAY INVISIBLE (-6025 3500);
FORCEPROP 1 LAST BODY_TYPE PLUMBING
J 2
(-6025 3550);
DISPLAY 0.872340 (-6025 3550);
PAINT GREEN (-6025 3550);
DISPLAY INVISIBLE (-6025 3550);
FORCEPROP 1 LAST HDL_TAP TRUE
J 2
(-6350 3375);
DISPLAY 0.872340 (-6350 3375);
DISPLAY INVISIBLE (-6350 3375);
FORCEPROP 1 LAST PATH I295
J 2
(-6023 3500);
DISPLAY 0.872340 (-6023 3500);
PAINT GREEN (-6023 3500);
DISPLAY INVISIBLE (-6023 3500);
FORCEADD TAP..1
R 2
(-6025 3450);
FORCEPROP 3 LASTPIN (-5975 3450) SIG_NAME M_E_CPU0_SB_CA<1>
J 0
(-5965 3460);
DISPLAY 0.659574 (-5965 3460);
PAINT MONO (-5965 3460);
DISPLAY INVISIBLE (-5965 3460);
FORCEPROP 1 LASTPIN (-5975 3450) BN 1
J 2
(-5963 3458);
DISPLAY 0.489362 (-5963 3458);
PAINT GREEN (-5963 3458);
FORCEPROP 2 LAST CDS_LIB mstr_standard
J 0
(-6025 3450);
DISPLAY 0.723404 (-6025 3450);
PAINT MONO (-6025 3450);
DISPLAY INVISIBLE (-6025 3450);
FORCEPROP 1 LAST BODY_TYPE PLUMBING
J 2
(-6025 3500);
DISPLAY 0.872340 (-6025 3500);
PAINT GREEN (-6025 3500);
DISPLAY INVISIBLE (-6025 3500);
FORCEPROP 1 LAST HDL_TAP TRUE
J 2
(-6350 3325);
DISPLAY 0.872340 (-6350 3325);
DISPLAY INVISIBLE (-6350 3325);
FORCEPROP 1 LAST PATH I296
J 2
(-6023 3450);
DISPLAY 0.872340 (-6023 3450);
PAINT GREEN (-6023 3450);
DISPLAY INVISIBLE (-6023 3450);
FORCEADD TAP..1
R 2
(-6025 3350);
FORCEPROP 3 LASTPIN (-5975 3350) SIG_NAME M_E_CPU0_SB_CA<3>
J 0
(-5965 3360);
DISPLAY 0.659574 (-5965 3360);
PAINT MONO (-5965 3360);
DISPLAY INVISIBLE (-5965 3360);
FORCEPROP 1 LASTPIN (-5975 3350) BN 3
J 2
(-5963 3358);
DISPLAY 0.489362 (-5963 3358);
PAINT GREEN (-5963 3358);
FORCEPROP 2 LAST CDS_LIB mstr_standard
J 0
(-6025 3350);
DISPLAY 0.723404 (-6025 3350);
PAINT MONO (-6025 3350);
DISPLAY INVISIBLE (-6025 3350);
FORCEPROP 1 LAST BODY_TYPE PLUMBING
J 2
(-6025 3400);
DISPLAY 0.872340 (-6025 3400);
PAINT GREEN (-6025 3400);
DISPLAY INVISIBLE (-6025 3400);
FORCEPROP 1 LAST HDL_TAP TRUE
J 2
(-6350 3225);
DISPLAY 0.872340 (-6350 3225);
DISPLAY INVISIBLE (-6350 3225);
FORCEPROP 1 LAST PATH I297
J 2
(-6023 3350);
DISPLAY 0.872340 (-6023 3350);
PAINT GREEN (-6023 3350);
DISPLAY INVISIBLE (-6023 3350);
FORCEADD TAP..1
R 2
(-6025 3400);
FORCEPROP 3 LASTPIN (-5975 3400) SIG_NAME M_E_CPU0_SB_CA<2>
J 0
(-5965 3410);
DISPLAY 0.659574 (-5965 3410);
PAINT MONO (-5965 3410);
DISPLAY INVISIBLE (-5965 3410);
FORCEPROP 1 LASTPIN (-5975 3400) BN 2
J 2
(-5963 3408);
DISPLAY 0.489362 (-5963 3408);
PAINT GREEN (-5963 3408);
FORCEPROP 2 LAST CDS_LIB mstr_standard
J 0
(-6025 3400);
DISPLAY 0.723404 (-6025 3400);
PAINT MONO (-6025 3400);
DISPLAY INVISIBLE (-6025 3400);
FORCEPROP 1 LAST BODY_TYPE PLUMBING
J 2
(-6025 3450);
DISPLAY 0.872340 (-6025 3450);
PAINT GREEN (-6025 3450);
DISPLAY INVISIBLE (-6025 3450);
FORCEPROP 1 LAST HDL_TAP TRUE
J 2
(-6350 3275);
DISPLAY 0.872340 (-6350 3275);
DISPLAY INVISIBLE (-6350 3275);
FORCEPROP 1 LAST PATH I298
J 2
(-6023 3400);
DISPLAY 0.872340 (-6023 3400);
PAINT GREEN (-6023 3400);
DISPLAY INVISIBLE (-6023 3400);
FORCEADD TAP..1
R 2
(-6025 3300);
FORCEPROP 3 LASTPIN (-5975 3300) SIG_NAME M_E_CPU0_SB_CA<4>
J 0
(-5965 3310);
DISPLAY 0.659574 (-5965 3310);
PAINT MONO (-5965 3310);
DISPLAY INVISIBLE (-5965 3310);
FORCEPROP 1 LASTPIN (-5975 3300) BN 4
J 2
(-5963 3308);
DISPLAY 0.489362 (-5963 3308);
PAINT GREEN (-5963 3308);
FORCEPROP 2 LAST CDS_LIB mstr_standard
J 0
(-6025 3300);
DISPLAY 0.723404 (-6025 3300);
PAINT MONO (-6025 3300);
DISPLAY INVISIBLE (-6025 3300);
FORCEPROP 1 LAST BODY_TYPE PLUMBING
J 2
(-6025 3350);
DISPLAY 0.872340 (-6025 3350);
PAINT GREEN (-6025 3350);
DISPLAY INVISIBLE (-6025 3350);
FORCEPROP 1 LAST HDL_TAP TRUE
J 2
(-6350 3175);
DISPLAY 0.872340 (-6350 3175);
DISPLAY INVISIBLE (-6350 3175);
FORCEPROP 1 LAST PATH I299
J 2
(-6023 3300);
DISPLAY 0.872340 (-6023 3300);
PAINT GREEN (-6023 3300);
DISPLAY INVISIBLE (-6023 3300);
FORCEADD TAP..1
R 2
(-6025 3250);
FORCEPROP 3 LASTPIN (-5975 3250) SIG_NAME M_E_CPU0_SB_CA<5>
J 0
(-5965 3260);
DISPLAY 0.659574 (-5965 3260);
PAINT MONO (-5965 3260);
DISPLAY INVISIBLE (-5965 3260);
FORCEPROP 1 LASTPIN (-5975 3250) BN 5
J 2
(-5963 3258);
DISPLAY 0.489362 (-5963 3258);
PAINT GREEN (-5963 3258);
FORCEPROP 2 LAST CDS_LIB mstr_standard
J 0
(-6025 3250);
DISPLAY 0.723404 (-6025 3250);
PAINT MONO (-6025 3250);
DISPLAY INVISIBLE (-6025 3250);
FORCEPROP 1 LAST BODY_TYPE PLUMBING
J 2
(-6025 3300);
DISPLAY 0.872340 (-6025 3300);
PAINT GREEN (-6025 3300);
DISPLAY INVISIBLE (-6025 3300);
FORCEPROP 1 LAST HDL_TAP TRUE
J 2
(-6350 3125);
DISPLAY 0.872340 (-6350 3125);
DISPLAY INVISIBLE (-6350 3125);
FORCEPROP 1 LAST PATH I300
J 2
(-6023 3250);
DISPLAY 0.872340 (-6023 3250);
PAINT GREEN (-6023 3250);
DISPLAY INVISIBLE (-6023 3250);
FORCEADD TAP..1
R 2
(-6025 3200);
FORCEPROP 3 LASTPIN (-5975 3200) SIG_NAME M_E_CPU0_SB_CA<6>
J 0
(-5965 3210);
DISPLAY 0.659574 (-5965 3210);
PAINT MONO (-5965 3210);
DISPLAY INVISIBLE (-5965 3210);
FORCEPROP 1 LASTPIN (-5975 3200) BN 6
J 2
(-5963 3208);
DISPLAY 0.489362 (-5963 3208);
PAINT GREEN (-5963 3208);
FORCEPROP 2 LAST CDS_LIB mstr_standard
J 0
(-6025 3200);
DISPLAY 0.723404 (-6025 3200);
PAINT MONO (-6025 3200);
DISPLAY INVISIBLE (-6025 3200);
FORCEPROP 1 LAST BODY_TYPE PLUMBING
J 2
(-6025 3250);
DISPLAY 0.872340 (-6025 3250);
PAINT GREEN (-6025 3250);
DISPLAY INVISIBLE (-6025 3250);
FORCEPROP 1 LAST HDL_TAP TRUE
J 2
(-6350 3075);
DISPLAY 0.872340 (-6350 3075);
DISPLAY INVISIBLE (-6350 3075);
FORCEPROP 1 LAST PATH I301
J 2
(-6023 3200);
DISPLAY 0.872340 (-6023 3200);
PAINT GREEN (-6023 3200);
DISPLAY INVISIBLE (-6023 3200);
FORCEADD OFFPAGE..2
R 2
(-6625 3525);
FORCEPROP 2 LAST $XR0 90 
J 0
(-6849 3525);
DISPLAY 0.638298 (-6849 3525);
PAINT MONO (-6849 3525);
FORCEPROP 2 LAST CDS_LIB standard
J 0
(-6625 3525);
DISPLAY INVISIBLE (-6625 3525);
FORCEPROP 1 LAST OFFPAGE TRUE
J 2
(-6950 3400);
DISPLAY 0.872340 (-6950 3400);
PAINT GREEN (-6950 3400);
DISPLAY INVISIBLE (-6950 3400);
FORCEPROP 1 LAST COMMENT_BODY TRUE
J 2
(-6580 3430);
DISPLAY 0.872340 (-6580 3430);
PAINT GREEN (-6580 3430);
DISPLAY INVISIBLE (-6580 3430);
FORCEPROP 2 LAST PATH I302
J 0
(-6875 3575);
DISPLAY 1.021277 (-6875 3575);
DISPLAY INVISIBLE (-6875 3575);
FORCEADD OFFPAGE..2
R 2
(-6625 3925);
FORCEPROP 2 LAST $XR0 90 
J 0
(-6849 3925);
DISPLAY 0.638298 (-6849 3925);
PAINT MONO (-6849 3925);
FORCEPROP 2 LAST CDS_LIB standard
J 0
(-6625 3925);
DISPLAY INVISIBLE (-6625 3925);
FORCEPROP 1 LAST OFFPAGE TRUE
J 2
(-6950 3800);
DISPLAY 0.872340 (-6950 3800);
PAINT GREEN (-6950 3800);
DISPLAY INVISIBLE (-6950 3800);
FORCEPROP 1 LAST COMMENT_BODY TRUE
J 2
(-6580 3830);
DISPLAY 0.872340 (-6580 3830);
PAINT GREEN (-6580 3830);
DISPLAY INVISIBLE (-6580 3830);
FORCEPROP 2 LAST PATH I303
J 0
(-6875 3975);
DISPLAY 1.021277 (-6875 3975);
DISPLAY INVISIBLE (-6875 3975);
FORCEADD OFFPAGE..2
R 2
(-6625 2850);
FORCEPROP 2 LAST $XR0 90 
J 0
(-6849 2850);
DISPLAY 0.638298 (-6849 2850);
PAINT MONO (-6849 2850);
FORCEPROP 2 LAST CDS_LIB standard
J 0
(-6625 2850);
DISPLAY INVISIBLE (-6625 2850);
FORCEPROP 1 LAST OFFPAGE TRUE
J 2
(-6950 2725);
DISPLAY 0.872340 (-6950 2725);
PAINT GREEN (-6950 2725);
DISPLAY INVISIBLE (-6950 2725);
FORCEPROP 1 LAST COMMENT_BODY TRUE
J 2
(-6580 2755);
DISPLAY 0.872340 (-6580 2755);
PAINT GREEN (-6580 2755);
DISPLAY INVISIBLE (-6580 2755);
FORCEPROP 2 LAST PATH I304
J 0
(-6875 2900);
DISPLAY 1.021277 (-6875 2900);
DISPLAY INVISIBLE (-6875 2900);
FORCEADD OFFPAGE..2
R 2
(-6625 2900);
FORCEPROP 2 LAST $XR0 90 
J 0
(-6849 2900);
DISPLAY 0.638298 (-6849 2900);
PAINT MONO (-6849 2900);
FORCEPROP 2 LAST CDS_LIB standard
J 0
(-6625 2900);
DISPLAY INVISIBLE (-6625 2900);
FORCEPROP 1 LAST OFFPAGE TRUE
J 2
(-6950 2775);
DISPLAY 0.872340 (-6950 2775);
PAINT GREEN (-6950 2775);
DISPLAY INVISIBLE (-6950 2775);
FORCEPROP 1 LAST COMMENT_BODY TRUE
J 2
(-6580 2805);
DISPLAY 0.872340 (-6580 2805);
PAINT GREEN (-6580 2805);
DISPLAY INVISIBLE (-6580 2805);
FORCEPROP 2 LAST PATH I305
J 0
(-6875 2950);
DISPLAY 1.021277 (-6875 2950);
DISPLAY INVISIBLE (-6875 2950);
FORCEADD OFFPAGE..2
R 2
(-6625 3000);
FORCEPROP 2 LAST $XR0 90 
J 0
(-6849 3000);
DISPLAY 0.638298 (-6849 3000);
PAINT MONO (-6849 3000);
FORCEPROP 2 LAST CDS_LIB standard
J 0
(-6625 3000);
DISPLAY INVISIBLE (-6625 3000);
FORCEPROP 1 LAST OFFPAGE TRUE
J 2
(-6950 2875);
DISPLAY 0.872340 (-6950 2875);
PAINT GREEN (-6950 2875);
DISPLAY INVISIBLE (-6950 2875);
FORCEPROP 1 LAST COMMENT_BODY TRUE
J 2
(-6580 2905);
DISPLAY 0.872340 (-6580 2905);
PAINT GREEN (-6580 2905);
DISPLAY INVISIBLE (-6580 2905);
FORCEPROP 2 LAST PATH I306
J 0
(-6875 3050);
DISPLAY 1.021277 (-6875 3050);
DISPLAY INVISIBLE (-6875 3050);
FORCEADD OFFPAGE..2
R 2
(-6625 3050);
FORCEPROP 2 LAST $XR0 90 
J 0
(-6849 3050);
DISPLAY 0.638298 (-6849 3050);
PAINT MONO (-6849 3050);
FORCEPROP 2 LAST CDS_LIB standard
J 0
(-6625 3050);
DISPLAY INVISIBLE (-6625 3050);
FORCEPROP 1 LAST OFFPAGE TRUE
J 2
(-6950 2925);
DISPLAY 0.872340 (-6950 2925);
PAINT GREEN (-6950 2925);
DISPLAY INVISIBLE (-6950 2925);
FORCEPROP 1 LAST COMMENT_BODY TRUE
J 2
(-6580 2955);
DISPLAY 0.872340 (-6580 2955);
PAINT GREEN (-6580 2955);
DISPLAY INVISIBLE (-6580 2955);
FORCEPROP 2 LAST PATH I307
J 0
(-6875 3100);
DISPLAY 1.021277 (-6875 3100);
DISPLAY INVISIBLE (-6875 3100);
FORCEADD OFFPAGE..5
(-6625 2100);
FORCEPROP 2 LAST $XR0 90 
J 0
(-6849 2100);
DISPLAY 0.638298 (-6849 2100);
PAINT MONO (-6849 2100);
FORCEPROP 2 LAST CDS_LIB standard
J 0
(-6625 2100);
DISPLAY INVISIBLE (-6625 2100);
FORCEPROP 1 LAST OFFPAGE TRUE
J 0
(-6300 1975);
DISPLAY 0.872340 (-6300 1975);
PAINT GREEN (-6300 1975);
DISPLAY INVISIBLE (-6300 1975);
FORCEPROP 1 LAST COMMENT_BODY TRUE
J 0
(-6525 2025);
DISPLAY 0.872340 (-6525 2025);
PAINT GREEN (-6525 2025);
DISPLAY INVISIBLE (-6525 2025);
FORCEPROP 2 LAST PATH I308
J 0
(-6875 2150);
DISPLAY 1.021277 (-6875 2150);
DISPLAY INVISIBLE (-6875 2150);
FORCEADD OFFPAGE..5
(-6625 2300);
FORCEPROP 2 LAST $XR0 90 
J 0
(-6849 2300);
DISPLAY 0.638298 (-6849 2300);
PAINT MONO (-6849 2300);
FORCEPROP 2 LAST CDS_LIB standard
J 0
(-6625 2300);
DISPLAY INVISIBLE (-6625 2300);
FORCEPROP 1 LAST OFFPAGE TRUE
J 0
(-6300 2175);
DISPLAY 0.872340 (-6300 2175);
PAINT GREEN (-6300 2175);
DISPLAY INVISIBLE (-6300 2175);
FORCEPROP 1 LAST COMMENT_BODY TRUE
J 0
(-6525 2225);
DISPLAY 0.872340 (-6525 2225);
PAINT GREEN (-6525 2225);
DISPLAY INVISIBLE (-6525 2225);
FORCEPROP 2 LAST PATH I309
J 0
(-6875 2350);
DISPLAY 1.021277 (-6875 2350);
DISPLAY INVISIBLE (-6875 2350);
FORCEADD OFFPAGE..2
R 2
(-6625 2500);
FORCEPROP 2 LAST $XR0 90 
J 0
(-6849 2500);
DISPLAY 0.638298 (-6849 2500);
PAINT MONO (-6849 2500);
FORCEPROP 2 LAST CDS_LIB standard
J 0
(-6625 2500);
DISPLAY INVISIBLE (-6625 2500);
FORCEPROP 1 LAST OFFPAGE TRUE
J 2
(-6950 2375);
DISPLAY 0.872340 (-6950 2375);
PAINT GREEN (-6950 2375);
DISPLAY INVISIBLE (-6950 2375);
FORCEPROP 1 LAST COMMENT_BODY TRUE
J 2
(-6580 2405);
DISPLAY 0.872340 (-6580 2405);
PAINT GREEN (-6580 2405);
DISPLAY INVISIBLE (-6580 2405);
FORCEPROP 2 LAST PATH I310
J 0
(-6875 2550);
DISPLAY 1.021277 (-6875 2550);
DISPLAY INVISIBLE (-6875 2550);
FORCEADD OFFPAGE..2
R 2
(-6625 2550);
FORCEPROP 2 LAST $XR0 90 
J 0
(-6849 2550);
DISPLAY 0.638298 (-6849 2550);
PAINT MONO (-6849 2550);
FORCEPROP 2 LAST CDS_LIB standard
J 0
(-6625 2550);
DISPLAY INVISIBLE (-6625 2550);
FORCEPROP 1 LAST OFFPAGE TRUE
J 2
(-6950 2425);
DISPLAY 0.872340 (-6950 2425);
PAINT GREEN (-6950 2425);
DISPLAY INVISIBLE (-6950 2425);
FORCEPROP 1 LAST COMMENT_BODY TRUE
J 2
(-6580 2455);
DISPLAY 0.872340 (-6580 2455);
PAINT GREEN (-6580 2455);
DISPLAY INVISIBLE (-6580 2455);
FORCEPROP 2 LAST PATH I311
J 0
(-6875 2600);
DISPLAY 1.021277 (-6875 2600);
DISPLAY INVISIBLE (-6875 2600);
FORCEADD OFFPAGE..5
(-6625 2650);
FORCEPROP 2 LAST $XR0 90 
J 0
(-6849 2650);
DISPLAY 0.638298 (-6849 2650);
PAINT MONO (-6849 2650);
FORCEPROP 2 LAST CDS_LIB mstr_standard
J 0
(-6625 2650);
DISPLAY INVISIBLE (-6625 2650);
FORCEPROP 1 LAST OFFPAGE TRUE
J 0
(-6300 2525);
DISPLAY 0.872340 (-6300 2525);
PAINT GREEN (-6300 2525);
DISPLAY INVISIBLE (-6300 2525);
FORCEPROP 1 LAST COMMENT_BODY TRUE
J 0
(-6525 2575);
DISPLAY 0.872340 (-6525 2575);
PAINT GREEN (-6525 2575);
DISPLAY INVISIBLE (-6525 2575);
FORCEPROP 2 LAST PATH I312
J 0
(-6875 2700);
DISPLAY 1.021277 (-6875 2700);
DISPLAY INVISIBLE (-6875 2700);
FORCEADD OFFPAGE..1
(-6625 2750);
FORCEPROP 2 LAST $XR0 90 
J 0
(-6846 2750);
DISPLAY 0.638298 (-6846 2750);
PAINT MONO (-6846 2750);
FORCEPROP 2 LAST CDS_LIB standard
J 0
(-6625 2750);
DISPLAY INVISIBLE (-6625 2750);
FORCEPROP 1 LAST OFFPAGE TRUE
J 0
(-6300 2625);
DISPLAY 0.872340 (-6300 2625);
PAINT GREEN (-6300 2625);
DISPLAY INVISIBLE (-6300 2625);
FORCEPROP 1 LAST COMMENT_BODY TRUE
J 0
(-6500 2650);
DISPLAY 0.872340 (-6500 2650);
PAINT GREEN (-6500 2650);
DISPLAY INVISIBLE (-6500 2650);
FORCEPROP 2 LAST PATH I313
J 0
(-6875 2800);
DISPLAY 1.021277 (-6875 2800);
DISPLAY INVISIBLE (-6875 2800);
FORCEADD OFFPAGE..1
(-6625 2400);
FORCEPROP 2 LAST $XR0 90 
J 0
(-6846 2400);
DISPLAY 0.638298 (-6846 2400);
PAINT MONO (-6846 2400);
FORCEPROP 2 LAST CDS_LIB standard
J 0
(-6625 2400);
DISPLAY INVISIBLE (-6625 2400);
FORCEPROP 1 LAST OFFPAGE TRUE
J 0
(-6300 2275);
DISPLAY 0.872340 (-6300 2275);
PAINT GREEN (-6300 2275);
DISPLAY INVISIBLE (-6300 2275);
FORCEPROP 1 LAST COMMENT_BODY TRUE
J 0
(-6500 2300);
DISPLAY 0.872340 (-6500 2300);
PAINT GREEN (-6500 2300);
DISPLAY INVISIBLE (-6500 2300);
FORCEPROP 2 LAST PATH I314
J 0
(-6875 2450);
DISPLAY 1.021277 (-6875 2450);
DISPLAY INVISIBLE (-6875 2450);
FORCEADD Q_RES..1
(-6950 2200);
FORCEPROP 1 LAST LOCATION R379
J 0
(-7275 2200);
DISPLAY 0.489362 (-7275 2200);
PAINT SKYBLUE (-7275 2200);
FORCEPROP 0 LAST $SEC 1
J 0
(-7125 2250);
DISPLAY 0.680851 (-7125 2250);
PAINT MONO (-7125 2250);
DISPLAY INVISIBLE (-7125 2250);
FORCEPROP 0 LAST CDS_SEC 1
J 0
(-7125 2250);
DISPLAY 1.021277 (-7125 2250);
DISPLAY INVISIBLE (-7125 2250);
FORCEPROP 1 LASTPIN (-7050 2200) $PN 1
J 0
(-7038 2212);
DISPLAY 0.489362 (-7038 2212);
PAINT MONO (-7038 2212);
FORCEPROP 1 LASTPIN (-6850 2200) $PN 2
J 0
(-6888 2212);
DISPLAY 0.489362 (-6888 2212);
PAINT MONO (-6888 2212);
FORCEPROP 1 LAST PACK_TYPE 0402LF
J 0
(-7275 2175);
DISPLAY 0.489362 (-7275 2175);
PAINT SKYBLUE (-7275 2175);
FORCEPROP 1 LAST TOLERANCE 1%
J 0
(-6675 2200);
DISPLAY 0.489362 (-6675 2200);
PAINT SKYBLUE (-6675 2200);
FORCEPROP 1 LAST VALUE 15
J 2
(-6625 2200);
DISPLAY 0.489362 (-6625 2200);
PAINT SKYBLUE (-6625 2200);
FORCEPROP 1 LAST MATERIAL CHIP
J 0
(-7075 2325);
DISPLAY 0.638298 (-7075 2325);
PAINT SKYBLUE (-7075 2325);
DISPLAY INVISIBLE (-7075 2325);
FORCEPROP 1 LAST WATTAGE 1/16W
J 2
(-6725 2325);
DISPLAY 0.638298 (-6725 2325);
PAINT SKYBLUE (-6725 2325);
DISPLAY INVISIBLE (-6725 2325);
FORCEPROP 2 LAST CDS_LIB pure_quanta
J 0
(-6950 2200);
DISPLAY INVISIBLE (-6950 2200);
FORCEPROP 1 LAST PATH I315
J 0
(-7000 2350);
DISPLAY 0.978723 (-7000 2350);
PAINT WHITE (-7000 2350);
DISPLAY INVISIBLE (-7000 2350);
FORCEPROP 1 LAST PART_NUMBER CS01502FB03
J 0
(-6850 2175);
DISPLAY 0.489362 (-6850 2175);
PAINT SKYBLUE (-6850 2175);
DISPLAY INVISIBLE (-6850 2175);
FORCEADD OFFPAGE..1
(-7825 2200);
FORCEPROP 2 LAST $XR0 90 
J 0
(-8046 2200);
DISPLAY 0.638298 (-8046 2200);
PAINT MONO (-8046 2200);
FORCEPROP 2 LAST CDS_LIB mstr_standard
J 0
(-7825 2200);
DISPLAY INVISIBLE (-7825 2200);
FORCEPROP 1 LAST OFFPAGE TRUE
J 0
(-7500 2075);
DISPLAY 0.872340 (-7500 2075);
PAINT GREEN (-7500 2075);
DISPLAY INVISIBLE (-7500 2075);
FORCEPROP 1 LAST COMMENT_BODY TRUE
J 0
(-7700 2100);
DISPLAY 0.872340 (-7700 2100);
PAINT GREEN (-7700 2100);
DISPLAY INVISIBLE (-7700 2100);
FORCEPROP 2 LAST PATH I316
J 0
(-8075 2250);
DISPLAY 1.021277 (-8075 2250);
DISPLAY INVISIBLE (-8075 2250);
FORCEADD QUANTA_TITLE_BLOCK_C..1
(-100 100);
FORCEPROP 0 LAST CDS_CON_LAST_MODIFIED Thu Sep 14 16:11:49 2023
J 0
(-1985 115);
DISPLAY INVISIBLE (-1985 115);
FORCEPROP 1 LAST CUSTOM_TXT_CDS <CON_LAST_MODIFIED>
J 0
(-1985 115);
DISPLAY 0.978723 (-1985 115);
FORCEPROP 2 LAST CUSTOM_TXT_CDS <XR_PAGE_TITLE>
J 0
(-7990 5350);
DISPLAY 0.638298 (-7990 5350);
PAINT PINK (-7990 5350);
DISPLAY INVISIBLE (-7990 5350);
FORCEPROP 1 LAST CUSTOM_TXT_CDS <NAME_2>
J 0
(-3275 150);
FORCEPROP 1 LAST CUSTOM_TXT_CDS <NAME_1>
J 0
(-3275 275);
FORCEPROP 1 LAST CUSTOM_TXT_CDS <Q_NUMBER>
J 0
(-1503 203);
DISPLAY 1.212766 (-1503 203);
FORCEPROP 1 LAST CUSTOM_TXT_CDS <Q_PROJ>
J 0
(-2482 202);
DISPLAY 1.212766 (-2482 202);
FORCEPROP 1 LAST CUSTOM_TXT_CDS <Q_REV>
J 0
(-284 203);
DISPLAY 1.212766 (-284 203);
FORCEPROP 1 LAST CUSTOM_TXT_CDS <CON_PAGE_NUM> OF <CON_TOTAL_PAGES>
J 0
(-546 118);
DISPLAY 0.978723 (-546 118);
FORCEPROP 1 LAST Q_TITLE CPU0 DDR CHE
J 0
(-9425 150);
DISPLAY 2.446809 (-9425 150);
PAINT GREEN (-9425 150);
FORCEPROP 2 LAST PAGE_BORDER TRUE
J 0
(-7990 5350);
DISPLAY 0.638298 (-7990 5350);
PAINT PINK (-7990 5350);
DISPLAY INVISIBLE (-7990 5350);
FORCEPROP 1 LAST CDS_LMAN_SYM_OUTLINE -9475,6775,100,-125
J 0
(-100 100);
DISPLAY 0.468085 (-100 100);
PAINT GREEN (-100 100);
DISPLAY INVISIBLE (-100 100);
FORCEPROP 2 LAST CDS_LIB pure_quanta
J 0
(-100 100);
DISPLAY INVISIBLE (-100 100);
FORCEPROP 2 LAST CDS_XR_PAGE_TITLE CR-14 : @T6G_MB_LIB.T6G(SCH_1):PAGE14
J 0
(-7990 5350);
DISPLAY 0.638298 (-7990 5350);
PAINT PINK (-7990 5350);
DISPLAY INVISIBLE (-7990 5350);
FORCEPROP 1 LAST Q_DEPT BU9
J 1
(-3863 149);
DISPLAY 1.957447 (-3863 149);
PAINT GREEN (-3863 149);
DISPLAY INVISIBLE (-3863 149);
FORCEPROP 1 LAST COMMENT_BODY TRUE
J 0
(-88 87);
DISPLAY 0.978723 (-88 87);
PAINT GREEN (-88 87);
DISPLAY INVISIBLE (-88 87);
FORCEADD CAD_NOTE..1
(-7725 2475);
FORCEPROP 0 LAST L1 R1953 PLACE CLOSE TO CPU < 25MM
J 0
(-7875 2350);
DISPLAY 0.617021 (-7875 2350);
PAINT WHITE (-7875 2350);
FORCEPROP 2 LAST CDS_LIB pure_quanta_power
J 0
(-7725 2475);
DISPLAY INVISIBLE (-7725 2475);
FORCEPROP 1 LAST COMMENT_BODY TRUE
J 0
(-7700 2575);
DISPLAY 0.574468 (-7700 2575);
PAINT WHITE (-7700 2575);
DISPLAY INVISIBLE (-7700 2575);
WIRE 17 -1 (-6075 4875)(-6075 4775);
WIRE 17 -1 (-6075 4975)(-6075 4875);
FORCEPROP 2 LAST SIG_NAME M_E_CPU0_SB_DQS_DN<9:0>
J 2
(-6110 4985);
DISPLAY 0.489362 (-6110 4985);
WIRE 17 -1 (-3350 2875)(-3350 2825);
WIRE 17 -1 (-3350 2925)(-3350 2875);
WIRE 17 -1 (-3350 2825)(-3350 2775);
WIRE 17 -1 (-3350 2725)(-3350 2775);
WIRE 17 -1 (-3350 3025)(-3350 2925);
WIRE 17 -1 (-3350 3075)(-3350 3025);
WIRE 17 -1 (-3350 2675)(-3350 2725);
WIRE 17 -1 (-3350 2625)(-3350 2675);
WIRE 17 -1 (-3350 3125)(-3350 3075);
WIRE 17 -1 (-3350 3175)(-3350 3125);
WIRE 17 -1 (-3350 2575)(-3350 2625);
WIRE 17 -1 (-3350 3225)(-3350 3175);
WIRE 17 -1 (-3350 3225)(-3350 3275);
WIRE 17 -1 (-3350 3275)(-3350 3325);
WIRE 17 -1 (-3350 3325)(-3350 3375);
WIRE 17 -1 (-3350 3375)(-3350 3475);
WIRE 17 -1 (-3350 3525)(-3350 3475);
WIRE 17 -1 (-3350 3575)(-3350 3525);
WIRE 17 -1 (-3350 3625)(-3350 3575);
WIRE 17 -1 (-3350 3675)(-3350 3625);
WIRE 17 -1 (-3350 3725)(-3350 3675);
WIRE 17 -1 (-3350 3775)(-3350 3725);
WIRE 17 -1 (-3350 3825)(-3350 3775);
WIRE 17 -1 (-3350 3925)(-3350 3825);
WIRE 17 -1 (-3350 3975)(-3350 3925);
WIRE 17 -1 (-3350 4025)(-3350 3975);
WIRE 17 -1 (-3350 4075)(-3350 4025);
WIRE 17 -1 (-3350 4125)(-3350 4075);
WIRE 17 -1 (-3350 4175)(-3350 4125);
WIRE 17 -1 (-3350 4225)(-3350 4175);
WIRE 17 -1 (-3350 4275)(-3350 4225);
WIRE 17 -1 (-3350 4275)(-2725 4275);
FORCEPROP 2 LAST SIG_NAME M_E_CPU0_SB_DQ<31:0>
J 2
(-2785 4285);
DISPLAY 0.489362 (-2785 4285);
WIRE 17 -1 (-3350 1725)(-3350 1775);
WIRE 17 -1 (-3350 1675)(-3350 1725);
WIRE 17 -1 (-3350 1775)(-3350 1825);
WIRE 17 -1 (-3350 1825)(-3350 1875);
WIRE 17 -1 (-3350 1925)(-3350 1875);
WIRE 17 -1 (-3350 1925)(-3350 1975);
WIRE 17 -1 (-3350 2025)(-3350 1975);
WIRE 17 -1 (-3350 2025)(-3350 2050);
WIRE 17 -1 (-3350 2050)(-2850 2050);
FORCEPROP 2 LAST SIG_NAME M_E_CPU0_SB_CB<7:0>
J 2
(-2850 2060);
DISPLAY 0.489362 (-2850 2060);
WIRE 17 -1 (-6075 5325)(-6075 5225);
WIRE 17 -1 (-6075 5325)(-6075 5425);
WIRE 17 -1 (-6075 5225)(-6075 5125);
WIRE 17 -1 (-6075 5425)(-6075 5525);
WIRE 17 -1 (-6075 5525)(-6075 5625);
WIRE 17 -1 (-6075 5725)(-6075 5625);
WIRE 17 -1 (-6075 5825)(-6075 5725);
WIRE 17 -1 (-6075 5925)(-6075 5825);
WIRE 17 -1 (-6075 6025)(-6075 5925);
FORCEPROP 2 LAST SIG_NAME M_E_CPU0_SA_DQS_DN<9:0>
J 2
(-6110 6035);
DISPLAY 0.489362 (-6110 6035);
WIRE 17 -1 (-5875 5575)(-5875 5675);
WIRE 17 -1 (-5875 5475)(-5875 5575);
WIRE 17 -1 (-5875 5775)(-5875 5675);
WIRE 17 -1 (-5875 5875)(-5875 5775);
WIRE 17 -1 (-5875 5375)(-5875 5475);
WIRE 17 -1 (-5875 5375)(-5875 5275);
WIRE 17 -1 (-5875 5975)(-5875 5875);
WIRE 17 -1 (-5875 6075)(-5875 5975);
WIRE 17 -1 (-5875 5275)(-5875 5175);
WIRE 17 -1 (-5875 6075)(-6675 6075);
FORCEPROP 2 LAST SIG_NAME M_E_CPU0_SA_DQS_DP<9:0>
J 2
(-6110 6085);
DISPLAY 0.489362 (-6110 6085);
WIRE 17 -1 (-6075 4775)(-6075 4675);
WIRE 17 -1 (-6075 4675)(-6075 4575);
WIRE 17 -1 (-6075 4475)(-6075 4575);
WIRE 17 -1 (-6075 4375)(-6075 4475);
WIRE 17 -1 (-5875 5025)(-5875 4925);
WIRE 17 -1 (-5875 5025)(-6675 5025);
FORCEPROP 2 LAST SIG_NAME M_E_CPU0_SB_DQS_DP<9:0>
J 2
(-6110 5035);
DISPLAY 0.489362 (-6110 5035);
WIRE 17 -1 (-6075 4275)(-6075 4375);
WIRE 17 -1 (-6075 4275)(-6075 4175);
WIRE 17 -1 (-3350 6075)(-2725 6075);
FORCEPROP 2 LAST SIG_NAME M_E_CPU0_SA_DQ<31:0>
J 2
(-2785 6085);
DISPLAY 0.489362 (-2785 6085);
WIRE 17 -1 (-6075 4175)(-6075 4075);
WIRE 17 -1 (-5875 4925)(-5875 4825);
WIRE 17 -1 (-5875 4825)(-5875 4725);
WIRE 17 -1 (-5875 4725)(-5875 4625);
WIRE 17 -1 (-3350 4425)(-3350 4475);
WIRE 17 -1 (-3350 4375)(-3350 4425);
WIRE 17 -1 (-3350 4475)(-3350 4525);
WIRE 17 -1 (-3350 4525)(-3350 4575);
WIRE 17 -1 (-3350 4625)(-3350 4575);
WIRE 17 -1 (-3350 4675)(-3350 4625);
WIRE 17 -1 (-3350 4725)(-3350 4675);
WIRE 17 -1 (-3350 4825)(-3350 4725);
WIRE 17 -1 (-3350 4875)(-3350 4825);
WIRE 17 -1 (-3350 4925)(-3350 4875);
WIRE 17 -1 (-3350 4975)(-3350 4925);
WIRE 17 -1 (-3350 5025)(-3350 4975);
WIRE 17 -1 (-3350 5025)(-3350 5075);
WIRE 17 -1 (-3350 5075)(-3350 5125);
WIRE 17 -1 (-3350 5125)(-3350 5175);
WIRE 17 -1 (-3350 5175)(-3350 5275);
WIRE 17 -1 (-3350 5325)(-3350 5275);
WIRE 17 -1 (-3350 5375)(-3350 5325);
WIRE 17 -1 (-3350 5425)(-3350 5375);
WIRE 17 -1 (-3350 5475)(-3350 5425);
WIRE 17 -1 (-3350 5525)(-3350 5475);
WIRE 17 -1 (-3350 5575)(-3350 5525);
WIRE 17 -1 (-3350 5625)(-3350 5575);
WIRE 17 -1 (-3350 5725)(-3350 5625);
WIRE 17 -1 (-3350 5775)(-3350 5725);
WIRE 17 -1 (-3350 5825)(-3350 5775);
WIRE 17 -1 (-3350 5875)(-3350 5825);
WIRE 17 -1 (-3350 5925)(-3350 5875);
WIRE 17 -1 (-3350 5975)(-3350 5925);
WIRE 17 -1 (-3350 6025)(-3350 5975);
WIRE 17 -1 (-3350 6075)(-3350 6025);
WIRE 17 -1 (-5875 4525)(-5875 4625);
WIRE 17 -1 (-3350 2475)(-3350 2500);
WIRE 17 -1 (-3350 2475)(-3350 2425);
WIRE 17 -1 (-3350 2500)(-2850 2500);
FORCEPROP 2 LAST SIG_NAME M_E_CPU0_SA_CB<7:0>
J 2
(-2850 2510);
DISPLAY 0.489362 (-2850 2510);
WIRE 17 -1 (-6075 3875)(-6075 3925);
WIRE 17 -1 (-6075 3825)(-6075 3875);
WIRE 17 -1 (-6075 3925)(-6575 3925);
FORCEPROP 2 LAST SIG_NAME M_E_CPU0_SA_CA<6:0>
J 0
(-6575 3935);
DISPLAY 0.489362 (-6575 3935);
WIRE 17 -1 (-5875 4425)(-5875 4525);
WIRE 17 -1 (-5875 4325)(-5875 4425);
WIRE 17 -1 (-5875 4325)(-5875 4225);
WIRE 17 -1 (-6075 3475)(-6075 3525);
WIRE 17 -1 (-6075 3425)(-6075 3475);
WIRE 17 -1 (-6075 3525)(-6575 3525);
FORCEPROP 2 LAST SIG_NAME M_E_CPU0_SB_CA<6:0>
J 0
(-6575 3535);
DISPLAY 0.489362 (-6575 3535);
WIRE 17 -1 (-3350 2375)(-3350 2425);
WIRE 17 -1 (-3350 2375)(-3350 2325);
WIRE 17 -1 (-5875 4225)(-5875 4125);
WIRE 17 -1 (-3350 2275)(-3350 2325);
WIRE 17 -1 (-3350 2225)(-3350 2275);
WIRE 17 -1 (-6075 3775)(-6075 3825);
WIRE 17 -1 (-6075 3375)(-6075 3425);
WIRE 17 -1 (-3350 2175)(-3350 2225);
WIRE 17 -1 (-3350 2125)(-3350 2175);
WIRE 17 -1 (-6075 3725)(-6075 3775);
WIRE 17 -1 (-6075 3675)(-6075 3725);
WIRE 17 -1 (-6075 3625)(-6075 3675);
WIRE 17 -1 (-6075 3325)(-6075 3375);
WIRE 17 -1 (-6075 3275)(-6075 3325);
WIRE 17 -1 (-6075 3225)(-6075 3275);
WIRE 17 -1 (-6075 4975)(-6675 4975);
WIRE 17 -1 (-6075 6025)(-6675 6025);
WIRE 16 -1 (-6575 1250)(-5475 1250);
FORCEPROP 2 LAST SIG_NAME TP_M_E_CPU0_SA_TEST39E
J 0
(-6560 1260);
DISPLAY 0.489362 (-6560 1260);
FORCEPROP 2 LASTPROP $XRERR UNIQUE?
J 0
(-6815 1250);
DISPLAY 0.638298 (-6815 1250);
PAINT MONO (-6815 1250);
DISPLAY INVISIBLE (-6815 1250);
WIRE 16 -1 (-6575 3000)(-5475 3000);
FORCEPROP 2 LAST SIG_NAME M_E_CPU0_CLK_DN<0>
J 0
(-6575 3010);
DISPLAY 0.489362 (-6575 3010);
WIRE 16 -1 (-6575 3050)(-5475 3050);
FORCEPROP 2 LAST SIG_NAME M_E_CPU0_CLK_DP<0>
J 0
(-6575 3060);
DISPLAY 0.489362 (-6575 3060);
WIRE 16 -1 (-5775 4100)(-5475 4100);
WIRE 16 -1 (-6575 2300)(-5475 2300);
FORCEPROP 2 LAST SIG_NAME M_E_CPU0_SB_PAR
J 0
(-6575 2310);
DISPLAY 0.489362 (-6575 2310);
WIRE 16 -1 (-6575 2650)(-5475 2650);
FORCEPROP 2 LAST SIG_NAME M_E_CPU0_SA_PAR
J 0
(-6575 2660);
DISPLAY 0.489362 (-6575 2660);
WIRE 16 -1 (-5775 5750)(-5475 5750);
WIRE 16 -1 (-5975 5300)(-5475 5300);
WIRE 16 -1 (-3875 1750)(-3450 1750);
WIRE 16 -1 (-3875 3500)(-3450 3500);
WIRE 16 -1 (-3875 2850)(-3450 2850);
WIRE 16 -1 (-5975 4850)(-5475 4850);
WIRE 16 -1 (-3875 5000)(-3450 5000);
WIRE 16 -1 (-5775 5850)(-5475 5850);
WIRE 16 -1 (-5975 5400)(-5475 5400);
WIRE 16 -1 (-3875 1800)(-3450 1800);
WIRE 16 -1 (-3875 3550)(-3450 3550);
WIRE 16 -1 (-3875 2900)(-3450 2900);
WIRE 16 -1 (-5975 4950)(-5475 4950);
WIRE 16 -1 (-3875 5050)(-3450 5050);
WIRE 16 -1 (-3875 4450)(-3450 4450);
WIRE 16 -1 (-5775 5950)(-5475 5950);
WIRE 16 -1 (-5975 5500)(-5475 5500);
WIRE 16 -1 (-3875 1850)(-3450 1850);
WIRE 16 -1 (-3875 3600)(-3450 3600);
WIRE 16 -1 (-3875 3000)(-3450 3000);
WIRE 16 -1 (-3875 5100)(-3450 5100);
WIRE 16 -1 (-3875 4500)(-3450 4500);
WIRE 16 -1 (-5775 6050)(-5475 6050);
WIRE 16 -1 (-5975 5600)(-5475 5600);
WIRE 16 -1 (-3450 1900)(-3875 1900);
WIRE 16 -1 (-3875 3750)(-3450 3750);
WIRE 16 -1 (-3875 3650)(-3450 3650);
WIRE 16 -1 (-3875 3050)(-3450 3050);
WIRE 16 -1 (-6575 2750)(-5475 2750);
FORCEPROP 2 LAST SIG_NAME M_E_CPU0_SA_RSP<0>
J 0
(-6575 2760);
DISPLAY 0.489362 (-6575 2760);
WIRE 16 -1 (-3875 2100)(-3450 2100);
WIRE 16 -1 (-3875 5550)(-3450 5550);
WIRE 16 -1 (-3875 5150)(-3450 5150);
WIRE 16 -1 (-3875 4550)(-3450 4550);
WIRE 16 -1 (-5975 5700)(-5475 5700);
WIRE 16 -1 (-5975 3200)(-5475 3200);
WIRE 16 -1 (-3875 1950)(-3450 1950);
WIRE 16 -1 (-3875 3800)(-3450 3800);
WIRE 16 -1 (-3875 3700)(-3450 3700);
WIRE 16 -1 (-3875 3100)(-3450 3100);
WIRE 16 -1 (-5975 3600)(-5475 3600);
WIRE 16 -1 (-3875 2150)(-3450 2150);
WIRE 16 -1 (-3875 5600)(-3450 5600);
WIRE 16 -1 (-3875 5250)(-3450 5250);
WIRE 16 -1 (-3875 4600)(-3450 4600);
WIRE 16 -1 (-5975 5800)(-5475 5800);
WIRE 16 -1 (-5975 3250)(-5475 3250);
WIRE 16 -1 (-3875 2000)(-3450 2000);
WIRE 16 -1 (-3875 3900)(-3450 3900);
WIRE 16 -1 (-3875 3150)(-3450 3150);
WIRE 16 -1 (-3875 2550)(-3450 2550);
WIRE 16 -1 (-5975 3650)(-5475 3650);
WIRE 16 -1 (-3875 2200)(-3450 2200);
WIRE 16 -1 (-3875 5700)(-3450 5700);
WIRE 16 -1 (-3875 5300)(-3450 5300);
WIRE 16 -1 (-3875 4650)(-3450 4650);
WIRE 16 -1 (-5975 5900)(-5475 5900);
WIRE 16 -1 (-6575 2500)(-5475 2500);
FORCEPROP 2 LAST SIG_NAME M_E_CPU0_SB_CS_N<1>
J 0
(-6575 2510);
DISPLAY 0.489362 (-6575 2510);
WIRE 16 -1 (-5975 3300)(-5475 3300);
WIRE 16 -1 (-3875 3950)(-3450 3950);
WIRE 16 -1 (-3875 2600)(-3450 2600);
WIRE 16 -1 (-5775 4200)(-5475 4200);
WIRE 16 -1 (-5975 3700)(-5475 3700);
WIRE 16 -1 (-3875 2250)(-3450 2250);
WIRE 16 -1 (-3875 5750)(-3450 5750);
WIRE 16 -1 (-3875 5350)(-3450 5350);
WIRE 16 -1 (-3875 4700)(-3450 4700);
WIRE 16 -1 (-5975 6000)(-5475 6000);
WIRE 16 -1 (-6575 2550)(-5475 2550);
FORCEPROP 2 LAST SIG_NAME M_E_CPU0_SB_CS_N<0>
J 0
(-6575 2560);
DISPLAY 0.489362 (-6575 2560);
WIRE 16 -1 (-5975 3350)(-5475 3350);
WIRE 16 -1 (-3875 4000)(-3450 4000);
WIRE 16 -1 (-5775 4300)(-5475 4300);
WIRE 16 -1 (-5975 3750)(-5475 3750);
WIRE 16 -1 (-3875 2300)(-3450 2300);
WIRE 16 -1 (-3875 5800)(-3450 5800);
WIRE 16 -1 (-3875 5400)(-3450 5400);
WIRE 16 -1 (-3875 4800)(-3450 4800);
WIRE 16 -1 (-5975 3400)(-5475 3400);
WIRE 16 -1 (-3875 4050)(-3450 4050);
WIRE 16 -1 (-5775 4400)(-5475 4400);
WIRE 16 -1 (-5975 3800)(-5475 3800);
WIRE 16 -1 (-3875 2350)(-3450 2350);
WIRE 16 -1 (-3875 5850)(-3450 5850);
WIRE 16 -1 (-3875 5450)(-3450 5450);
WIRE 16 -1 (-3875 4850)(-3450 4850);
WIRE 16 -1 (-5975 3450)(-5475 3450);
WIRE 16 -1 (-3875 4100)(-3450 4100);
WIRE 16 -1 (-5775 4500)(-5475 4500);
WIRE 16 -1 (-5975 4050)(-5475 4050);
WIRE 16 -1 (-5975 3850)(-5475 3850);
WIRE 16 -1 (-3875 2400)(-3450 2400);
WIRE 16 -1 (-3875 5900)(-3450 5900);
WIRE 16 -1 (-3875 5500)(-3450 5500);
WIRE 16 -1 (-3875 4900)(-3450 4900);
WIRE 16 -1 (-5975 3500)(-5475 3500);
WIRE 16 -1 (-3875 4150)(-3450 4150);
WIRE 16 -1 (-5775 4600)(-5475 4600);
WIRE 16 -1 (-5975 4150)(-5475 4150);
WIRE 16 -1 (-5975 3900)(-5475 3900);
WIRE 16 -1 (-3875 2450)(-3450 2450);
WIRE 16 -1 (-3875 5950)(-3450 5950);
WIRE 16 -1 (-3875 4950)(-3450 4950);
WIRE 16 -1 (-3875 4350)(-3450 4350);
WIRE 16 -1 (-5775 5150)(-5475 5150);
WIRE 16 -1 (-3875 4200)(-3450 4200);
WIRE 16 -1 (-5775 4700)(-5475 4700);
WIRE 16 -1 (-5975 4250)(-5475 4250);
WIRE 16 -1 (-6575 2850)(-5475 2850);
FORCEPROP 2 LAST SIG_NAME M_E_CPU0_SA_CS_N<1>
J 0
(-6575 2860);
DISPLAY 0.489362 (-6575 2860);
WIRE 16 -1 (-3875 6000)(-3450 6000);
WIRE 16 -1 (-3875 4400)(-3450 4400);
WIRE 16 -1 (-5775 5250)(-5475 5250);
WIRE 16 -1 (-3875 4250)(-3450 4250);
WIRE 16 -1 (-3875 3200)(-3450 3200);
WIRE 16 -1 (-5775 4800)(-5475 4800);
WIRE 16 -1 (-5975 4350)(-5475 4350);
WIRE 16 -1 (-6575 2900)(-5475 2900);
FORCEPROP 2 LAST SIG_NAME M_E_CPU0_SA_CS_N<0>
J 0
(-6575 2910);
DISPLAY 0.489362 (-6575 2910);
WIRE 16 -1 (-3875 6050)(-3450 6050);
WIRE 16 -1 (-5775 5350)(-5475 5350);
WIRE 16 -1 (-3875 3250)(-3450 3250);
WIRE 16 -1 (-3875 2650)(-3450 2650);
WIRE 16 -1 (-5775 4900)(-5475 4900);
WIRE 16 -1 (-5975 4450)(-5475 4450);
WIRE 16 -1 (-5775 5450)(-5475 5450);
WIRE 16 -1 (-3875 3300)(-3450 3300);
WIRE 16 -1 (-3875 2700)(-3450 2700);
WIRE 16 -1 (-5775 5000)(-5475 5000);
WIRE 16 -1 (-5975 4550)(-5475 4550);
WIRE 16 -1 (-5775 5550)(-5475 5550);
WIRE 16 -1 (-5975 5100)(-5475 5100);
WIRE 16 -1 (-6575 2400)(-5475 2400);
FORCEPROP 2 LAST SIG_NAME M_E_CPU0_SB_RSP<0>
J 0
(-6575 2410);
DISPLAY 0.489362 (-6575 2410);
WIRE 16 -1 (-3875 1650)(-3450 1650);
WIRE 16 -1 (-3875 3350)(-3450 3350);
WIRE 16 -1 (-3875 2750)(-3450 2750);
WIRE 16 -1 (-5975 4650)(-5475 4650);
WIRE 16 -1 (-5775 5650)(-5475 5650);
WIRE 16 -1 (-5975 5200)(-5475 5200);
WIRE 16 -1 (-3875 1700)(-3450 1700);
WIRE 16 -1 (-3875 3450)(-3450 3450);
WIRE 16 -1 (-3875 2800)(-3450 2800);
WIRE 16 -1 (-5975 4750)(-5475 4750);
WIRE 16 -1 (-6575 2100)(-5475 2100);
FORCEPROP 2 LAST SIG_NAME M_E_CPU0_RESET_N
J 0
(-6575 2110);
DISPLAY 0.489362 (-6575 2110);
WIRE 16 -1 (-6850 2200)(-5475 2200);
FORCEPROP 2 LAST SIG_NAME M_E_CPU0_ALERT_R_N
J 0
(-6560 2210);
DISPLAY 0.489362 (-6560 2210);
FORCEPROP 2 LASTPROP $XRERR UNIQUE?
J 0
(-6800 2210);
DISPLAY 0.638298 (-6800 2210);
PAINT MONO (-6800 2210);
DISPLAY INVISIBLE (-6800 2210);
WIRE 16 -1 (-7775 2200)(-7050 2200);
FORCEPROP 2 LAST SIG_NAME M_E_CPU0_ALERT_N
J 0
(-7735 2210);
DISPLAY 0.489362 (-7735 2210);
QUIT
